(kicad_sch
	(version 20250114)
	(generator "eeschema")
	(generator_version "9.0")
	(paper "A3")
	(title_block
		(title "Antmicro Baseboard for Jetson AGX Thor")
		(date "2026-02-17")
		(rev "1.1.0")
		(company "Antmicro Ltd")
		(comment 1 "www.antmicro.com")
	)
	(text "Debug USB-C 0"
		(exclude_from_sim no)
		(at 213.614 23.114 0)
		(effects
			(font
				(size 2.54 2.54)
				(thickness 0.8)
				(bold yes)
			)
			(justify right bottom)
		)
	)
	(text "I2C addr:\nC1: 0x43\nC2: 0x47"
		(exclude_from_sim no)
		(at 191.262 267.97 0)
		(effects
			(font
				(size 1.27 1.27)
			)
		)
	)
	(text "USB PORT 0"
		(exclude_from_sim no)
		(at 340.106 65.532 0)
		(effects
			(font
				(size 1.27 1.27)
				(thickness 0.254)
				(bold yes)
			)
		)
	)
	(text "pinout compatible with \nwww.github.com/antmicro/ftdi-toolkit "
		(exclude_from_sim no)
		(at 18.288 180.594 0)
		(effects
			(font
				(size 2 2)
			)
			(justify left bottom)
		)
	)
	(text "USB PD controller"
		(exclude_from_sim no)
		(at 201.422 172.212 0)
		(effects
			(font
				(size 2.54 2.54)
				(thickness 0.508)
				(bold yes)
			)
		)
	)
	(text "Debug connector"
		(exclude_from_sim no)
		(at 17.78 173.482 0)
		(effects
			(font
				(size 2.54 2.54)
				(thickness 0.8)
				(bold yes)
			)
			(justify left bottom)
		)
	)
	(text "TX\n"
		(exclude_from_sim no)
		(at 111.76 99.695 0)
		(effects
			(font
				(size 1.27 1.27)
			)
			(justify right bottom)
		)
	)
	(text "USB-PD Source/Sink"
		(exclude_from_sim no)
		(at 213.614 27.94 0)
		(effects
			(font
				(size 2 2)
				(bold yes)
			)
			(justify right bottom)
		)
	)
	(text "RX"
		(exclude_from_sim no)
		(at 125.73 99.695 0)
		(effects
			(font
				(size 1.27 1.27)
			)
			(justify right bottom)
		)
	)
	(text "NOTE:\nDevice set to\nconfiguration 1\nDFP only\n5V at 3A Source capability"
		(exclude_from_sim no)
		(at 125.476 243.586 0)
		(effects
			(font
				(size 1.27 1.27)
			)
			(justify left)
		)
	)
	(text "20V 5A"
		(exclude_from_sim no)
		(at 201.168 177.546 0)
		(effects
			(font
				(size 2 2)
				(thickness 0.4)
				(bold yes)
			)
		)
	)
	(junction
		(at 69.85 256.54)
		(diameter 0)
		(color 0 0 0 0)
	)
	(junction
		(at 240.03 250.19)
		(diameter 0)
		(color 0 0 0 0)
	)
	(junction
		(at 97.79 128.27)
		(diameter 0)
		(color 0 0 0 0)
	)
	(junction
		(at 71.12 99.06)
		(diameter 0)
		(color 0 0 0 0)
	)
	(junction
		(at 39.37 214.63)
		(diameter 0)
		(color 0 0 0 0)
	)
	(junction
		(at 306.07 81.28)
		(diameter 0)
		(color 0 0 0 0)
	)
	(junction
		(at 162.56 64.77)
		(diameter 0)
		(color 0 0 0 0)
	)
	(junction
		(at 360.68 194.31)
		(diameter 0)
		(color 0 0 0 0)
	)
	(junction
		(at 328.93 210.82)
		(diameter 0)
		(color 0 0 0 0)
	)
	(junction
		(at 134.62 64.77)
		(diameter 0)
		(color 0 0 0 0)
	)
	(junction
		(at 86.36 144.78)
		(diameter 0)
		(color 0 0 0 0)
	)
	(junction
		(at 113.03 64.77)
		(diameter 0)
		(color 0 0 0 0)
	)
	(junction
		(at 179.07 260.35)
		(diameter 0)
		(color 0 0 0 0)
	)
	(junction
		(at 234.95 245.11)
		(diameter 0)
		(color 0 0 0 0)
	)
	(junction
		(at 337.82 31.75)
		(diameter 0)
		(color 0 0 0 0)
	)
	(junction
		(at 240.03 217.17)
		(diameter 0)
		(color 0 0 0 0)
	)
	(junction
		(at 146.05 185.42)
		(diameter 0)
		(color 0 0 0 0)
	)
	(junction
		(at 327.66 31.75)
		(diameter 0)
		(color 0 0 0 0)
	)
	(junction
		(at 359.41 31.75)
		(diameter 0)
		(color 0 0 0 0)
	)
	(junction
		(at 214.63 74.93)
		(diameter 0)
		(color 0 0 0 0)
	)
	(junction
		(at 245.11 217.17)
		(diameter 0)
		(color 0 0 0 0)
	)
	(junction
		(at 199.39 114.3)
		(diameter 0)
		(color 0 0 0 0)
	)
	(junction
		(at 195.58 99.06)
		(diameter 0)
		(color 0 0 0 0)
	)
	(junction
		(at 86.36 116.84)
		(diameter 0)
		(color 0 0 0 0)
	)
	(junction
		(at 209.55 54.61)
		(diameter 0)
		(color 0 0 0 0)
	)
	(junction
		(at 261.62 25.4)
		(diameter 0)
		(color 0 0 0 0)
	)
	(junction
		(at 170.18 227.33)
		(diameter 0)
		(color 0 0 0 0)
	)
	(junction
		(at 300.99 73.66)
		(diameter 0)
		(color 0 0 0 0)
	)
	(junction
		(at 274.32 34.29)
		(diameter 0)
		(color 0 0 0 0)
	)
	(junction
		(at 90.17 114.3)
		(diameter 0)
		(color 0 0 0 0)
	)
	(junction
		(at 242.57 217.17)
		(diameter 0)
		(color 0 0 0 0)
	)
	(junction
		(at 339.09 210.82)
		(diameter 0)
		(color 0 0 0 0)
	)
	(junction
		(at 170.18 215.9)
		(diameter 0)
		(color 0 0 0 0)
	)
	(junction
		(at 39.37 204.47)
		(diameter 0)
		(color 0 0 0 0)
	)
	(junction
		(at 274.32 25.4)
		(diameter 0)
		(color 0 0 0 0)
	)
	(junction
		(at 86.36 128.27)
		(diameter 0)
		(color 0 0 0 0)
	)
	(junction
		(at 245.11 260.35)
		(diameter 0)
		(color 0 0 0 0)
	)
	(junction
		(at 336.55 208.28)
		(diameter 0)
		(color 0 0 0 0)
	)
	(junction
		(at 270.51 110.49)
		(diameter 0)
		(color 0 0 0 0)
	)
	(junction
		(at 144.78 64.77)
		(diameter 0)
		(color 0 0 0 0)
	)
	(junction
		(at 364.49 194.31)
		(diameter 0)
		(color 0 0 0 0)
	)
	(junction
		(at 283.21 36.83)
		(diameter 0)
		(color 0 0 0 0)
	)
	(junction
		(at 303.53 78.74)
		(diameter 0)
		(color 0 0 0 0)
	)
	(junction
		(at 78.74 137.16)
		(diameter 0)
		(color 0 0 0 0)
	)
	(junction
		(at 308.61 71.12)
		(diameter 0)
		(color 0 0 0 0)
	)
	(junction
		(at 237.49 217.17)
		(diameter 0)
		(color 0 0 0 0)
	)
	(junction
		(at 306.07 41.91)
		(diameter 0)
		(color 0 0 0 0)
	)
	(junction
		(at 321.31 81.28)
		(diameter 0)
		(color 0 0 0 0)
	)
	(junction
		(at 321.31 66.04)
		(diameter 0)
		(color 0 0 0 0)
	)
	(junction
		(at 90.17 99.06)
		(diameter 0)
		(color 0 0 0 0)
	)
	(junction
		(at 242.57 257.81)
		(diameter 0)
		(color 0 0 0 0)
	)
	(junction
		(at 250.19 25.4)
		(diameter 0)
		(color 0 0 0 0)
	)
	(junction
		(at 347.98 31.75)
		(diameter 0)
		(color 0 0 0 0)
	)
	(junction
		(at 237.49 247.65)
		(diameter 0)
		(color 0 0 0 0)
	)
	(junction
		(at 153.67 64.77)
		(diameter 0)
		(color 0 0 0 0)
	)
	(junction
		(at 321.31 31.75)
		(diameter 0)
		(color 0 0 0 0)
	)
	(junction
		(at 261.62 36.83)
		(diameter 0)
		(color 0 0 0 0)
	)
	(junction
		(at 321.31 132.08)
		(diameter 0)
		(color 0 0 0 0)
	)
	(junction
		(at 120.65 64.77)
		(diameter 0)
		(color 0 0 0 0)
	)
	(junction
		(at 322.58 78.74)
		(diameter 0)
		(color 0 0 0 0)
	)
	(junction
		(at 138.43 185.42)
		(diameter 0)
		(color 0 0 0 0)
	)
	(junction
		(at 50.8 99.06)
		(diameter 0)
		(color 0 0 0 0)
	)
	(junction
		(at 306.07 34.29)
		(diameter 0)
		(color 0 0 0 0)
	)
	(junction
		(at 86.36 64.77)
		(diameter 0)
		(color 0 0 0 0)
	)
	(junction
		(at 149.86 215.9)
		(diameter 0)
		(color 0 0 0 0)
	)
	(junction
		(at 276.86 236.22)
		(diameter 0)
		(color 0 0 0 0)
	)
	(junction
		(at 195.58 101.6)
		(diameter 0)
		(color 0 0 0 0)
	)
	(junction
		(at 275.59 107.95)
		(diameter 0)
		(color 0 0 0 0)
	)
	(junction
		(at 214.63 54.61)
		(diameter 0)
		(color 0 0 0 0)
	)
	(no_connect
		(at 323.85 99.06)
	)
	(no_connect
		(at 323.85 91.44)
	)
	(no_connect
		(at 72.39 212.09)
	)
	(no_connect
		(at 171.45 104.14)
	)
	(no_connect
		(at 358.14 215.9)
	)
	(no_connect
		(at 323.85 116.84)
	)
	(no_connect
		(at 323.85 109.22)
	)
	(no_connect
		(at 256.54 81.28)
	)
	(no_connect
		(at 171.45 106.68)
	)
	(no_connect
		(at 323.85 124.46)
	)
	(no_connect
		(at 224.79 81.28)
	)
	(no_connect
		(at 217.17 227.33)
	)
	(no_connect
		(at 256.54 78.74)
	)
	(no_connect
		(at 323.85 121.92)
	)
	(no_connect
		(at 217.17 229.87)
	)
	(no_connect
		(at 323.85 93.98)
	)
	(no_connect
		(at 72.39 204.47)
	)
	(no_connect
		(at 323.85 101.6)
	)
	(no_connect
		(at 323.85 106.68)
	)
	(no_connect
		(at 323.85 114.3)
	)
	(bus_entry
		(at 281.94 248.92)
		(size -1.27 1.27)
		(stroke
			(width 0)
			(type default)
		)
	)
	(bus_entry
		(at 88.9 233.68)
		(size -1.27 1.27)
		(stroke
			(width 0)
			(type default)
		)
	)
	(bus_entry
		(at 88.9 231.14)
		(size -1.27 1.27)
		(stroke
			(width 0)
			(type default)
		)
	)
	(bus_entry
		(at 130.81 100.33)
		(size 1.27 1.27)
		(stroke
			(width 0)
			(type default)
		)
	)
	(bus_entry
		(at 82.55 252.73)
		(size -1.27 1.27)
		(stroke
			(width 0)
			(type default)
		)
	)
	(bus_entry
		(at 88.9 236.22)
		(size -1.27 1.27)
		(stroke
			(width 0)
			(type default)
		)
	)
	(bus_entry
		(at 281.94 246.38)
		(size -1.27 1.27)
		(stroke
			(width 0)
			(type default)
		)
	)
	(bus_entry
		(at 82.55 255.27)
		(size -1.27 1.27)
		(stroke
			(width 0)
			(type default)
		)
	)
	(bus_entry
		(at 88.9 238.76)
		(size -1.27 1.27)
		(stroke
			(width 0)
			(type default)
		)
	)
	(bus_entry
		(at 130.81 97.79)
		(size 1.27 1.27)
		(stroke
			(width 0)
			(type default)
		)
	)
	(wire
		(pts
			(xy 240.03 217.17) (xy 240.03 222.25)
		)
		(stroke
			(width 0)
			(type default)
		)
	)
	(wire
		(pts
			(xy 97.79 139.7) (xy 97.79 140.97)
		)
		(stroke
			(width 0)
			(type default)
		)
	)
	(wire
		(pts
			(xy 283.21 36.83) (xy 279.4 36.83)
		)
		(stroke
			(width 0)
			(type default)
		)
	)
	(bus
		(pts
			(xy 82.55 252.73) (xy 83.82 251.46)
		)
		(stroke
			(width 0)
			(type default)
		)
	)
	(wire
		(pts
			(xy 162.56 99.06) (xy 167.64 99.06)
		)
		(stroke
			(width 0)
			(type default)
		)
	)
	(wire
		(pts
			(xy 227.33 114.3) (xy 212.09 114.3)
		)
		(stroke
			(width 0)
			(type default)
		)
	)
	(wire
		(pts
			(xy 217.17 207.01) (xy 233.68 207.01)
		)
		(stroke
			(width 0)
			(type default)
		)
	)
	(wire
		(pts
			(xy 69.85 259.08) (xy 69.85 256.54)
		)
		(stroke
			(width 0)
			(type default)
		)
	)
	(wire
		(pts
			(xy 240.03 250.19) (xy 256.54 250.19)
		)
		(stroke
			(width 0)
			(type default)
		)
	)
	(wire
		(pts
			(xy 247.65 232.41) (xy 247.65 231.14)
		)
		(stroke
			(width 0)
			(type default)
		)
	)
	(wire
		(pts
			(xy 217.17 255.27) (xy 251.46 255.27)
		)
		(stroke
			(width 0)
			(type default)
		)
	)
	(wire
		(pts
			(xy 359.41 38.1) (xy 359.41 39.37)
		)
		(stroke
			(width 0)
			(type default)
		)
	)
	(wire
		(pts
			(xy 39.37 214.63) (xy 39.37 219.71)
		)
		(stroke
			(width 0)
			(type default)
		)
	)
	(bus
		(pts
			(xy 82.55 252.73) (xy 82.55 255.27)
		)
		(stroke
			(width 0)
			(type default)
		)
	)
	(wire
		(pts
			(xy 90.17 99.06) (xy 86.36 99.06)
		)
		(stroke
			(width 0)
			(type default)
		)
	)
	(wire
		(pts
			(xy 195.58 99.06) (xy 194.31 99.06)
		)
		(stroke
			(width 0)
			(type default)
		)
	)
	(wire
		(pts
			(xy 251.46 260.35) (xy 245.11 260.35)
		)
		(stroke
			(width 0)
			(type default)
		)
	)
	(wire
		(pts
			(xy 34.29 207.01) (xy 40.64 207.01)
		)
		(stroke
			(width 0)
			(type default)
		)
	)
	(wire
		(pts
			(xy 321.31 133.35) (xy 321.31 132.08)
		)
		(stroke
			(width 0)
			(type default)
		)
	)
	(wire
		(pts
			(xy 177.8 195.58) (xy 181.61 195.58)
		)
		(stroke
			(width 0)
			(type default)
		)
	)
	(wire
		(pts
			(xy 270.51 110.49) (xy 270.51 113.03)
		)
		(stroke
			(width 0)
			(type default)
		)
	)
	(wire
		(pts
			(xy 90.17 110.49) (xy 90.17 114.3)
		)
		(stroke
			(width 0)
			(type default)
		)
	)
	(wire
		(pts
			(xy 261.62 247.65) (xy 280.67 247.65)
		)
		(stroke
			(width 0)
			(type default)
		)
	)
	(wire
		(pts
			(xy 163.83 207.01) (xy 181.61 207.01)
		)
		(stroke
			(width 0)
			(type default)
		)
	)
	(wire
		(pts
			(xy 195.58 101.6) (xy 194.31 101.6)
		)
		(stroke
			(width 0)
			(type default)
		)
	)
	(wire
		(pts
			(xy 261.62 36.83) (xy 261.62 43.18)
		)
		(stroke
			(width 0)
			(type default)
		)
	)
	(wire
		(pts
			(xy 250.19 33.02) (xy 250.19 31.75)
		)
		(stroke
			(width 0)
			(type default)
		)
	)
	(wire
		(pts
			(xy 207.01 54.61) (xy 209.55 54.61)
		)
		(stroke
			(width 0)
			(type default)
		)
	)
	(wire
		(pts
			(xy 138.43 185.42) (xy 146.05 185.42)
		)
		(stroke
			(width 0)
			(type default)
		)
	)
	(wire
		(pts
			(xy 217.17 209.55) (xy 233.68 209.55)
		)
		(stroke
			(width 0)
			(type default)
		)
	)
	(wire
		(pts
			(xy 302.26 31.75) (xy 321.31 31.75)
		)
		(stroke
			(width 0)
			(type default)
		)
	)
	(wire
		(pts
			(xy 86.36 64.77) (xy 87.63 64.77)
		)
		(stroke
			(width 0)
			(type default)
		)
	)
	(wire
		(pts
			(xy 170.18 101.6) (xy 167.64 99.06)
		)
		(stroke
			(width 0)
			(type default)
		)
	)
	(wire
		(pts
			(xy 330.2 201.93) (xy 328.93 201.93)
		)
		(stroke
			(width 0)
			(type default)
		)
	)
	(wire
		(pts
			(xy 86.36 119.38) (xy 86.36 128.27)
		)
		(stroke
			(width 0)
			(type default)
		)
	)
	(wire
		(pts
			(xy 60.96 234.95) (xy 87.63 234.95)
		)
		(stroke
			(width 0)
			(type default)
		)
	)
	(wire
		(pts
			(xy 153.67 64.77) (xy 162.56 64.77)
		)
		(stroke
			(width 0)
			(type default)
		)
	)
	(wire
		(pts
			(xy 153.67 187.96) (xy 153.67 191.77)
		)
		(stroke
			(width 0)
			(type default)
		)
	)
	(wire
		(pts
			(xy 177.8 187.96) (xy 177.8 195.58)
		)
		(stroke
			(width 0)
			(type default)
		)
	)
	(wire
		(pts
			(xy 214.63 74.93) (xy 223.52 74.93)
		)
		(stroke
			(width 0)
			(type default)
		)
	)
	(wire
		(pts
			(xy 359.41 33.02) (xy 359.41 31.75)
		)
		(stroke
			(width 0)
			(type default)
		)
	)
	(wire
		(pts
			(xy 274.32 34.29) (xy 274.32 31.75)
		)
		(stroke
			(width 0)
			(type default)
		)
	)
	(wire
		(pts
			(xy 39.37 209.55) (xy 40.64 209.55)
		)
		(stroke
			(width 0)
			(type default)
		)
	)
	(wire
		(pts
			(xy 351.79 194.31) (xy 360.68 194.31)
		)
		(stroke
			(width 0)
			(type default)
		)
	)
	(wire
		(pts
			(xy 113.03 95.25) (xy 113.03 102.87)
		)
		(stroke
			(width 0)
			(type default)
		)
	)
	(wire
		(pts
			(xy 276.86 236.22) (xy 276.86 237.49)
		)
		(stroke
			(width 0)
			(type default)
		)
	)
	(wire
		(pts
			(xy 153.67 229.87) (xy 153.67 231.14)
		)
		(stroke
			(width 0)
			(type default)
		)
	)
	(wire
		(pts
			(xy 283.21 43.18) (xy 283.21 44.45)
		)
		(stroke
			(width 0)
			(type default)
		)
	)
	(wire
		(pts
			(xy 170.18 215.9) (xy 181.61 215.9)
		)
		(stroke
			(width 0)
			(type default)
		)
	)
	(wire
		(pts
			(xy 153.67 64.77) (xy 144.78 64.77)
		)
		(stroke
			(width 0)
			(type default)
		)
	)
	(wire
		(pts
			(xy 214.63 73.66) (xy 214.63 74.93)
		)
		(stroke
			(width 0)
			(type default)
		)
	)
	(wire
		(pts
			(xy 241.3 203.2) (xy 248.92 203.2)
		)
		(stroke
			(width 0)
			(type default)
		)
	)
	(wire
		(pts
			(xy 161.29 196.85) (xy 161.29 198.12)
		)
		(stroke
			(width 0)
			(type default)
		)
	)
	(wire
		(pts
			(xy 271.78 236.22) (xy 276.86 236.22)
		)
		(stroke
			(width 0)
			(type default)
		)
	)
	(wire
		(pts
			(xy 194.31 107.95) (xy 259.08 107.95)
		)
		(stroke
			(width 0)
			(type default)
		)
	)
	(wire
		(pts
			(xy 214.63 74.93) (xy 214.63 76.2)
		)
		(stroke
			(width 0)
			(type default)
		)
	)
	(wire
		(pts
			(xy 364.49 194.31) (xy 364.49 196.85)
		)
		(stroke
			(width 0)
			(type default)
		)
	)
	(wire
		(pts
			(xy 153.67 218.44) (xy 153.67 219.71)
		)
		(stroke
			(width 0)
			(type default)
		)
	)
	(wire
		(pts
			(xy 283.21 38.1) (xy 283.21 36.83)
		)
		(stroke
			(width 0)
			(type default)
		)
	)
	(wire
		(pts
			(xy 107.95 67.31) (xy 109.22 67.31)
		)
		(stroke
			(width 0)
			(type default)
		)
	)
	(wire
		(pts
			(xy 321.31 31.75) (xy 321.31 66.04)
		)
		(stroke
			(width 0)
			(type default)
		)
	)
	(wire
		(pts
			(xy 170.18 227.33) (xy 181.61 227.33)
		)
		(stroke
			(width 0)
			(type default)
		)
	)
	(wire
		(pts
			(xy 223.52 54.61) (xy 214.63 54.61)
		)
		(stroke
			(width 0)
			(type default)
		)
	)
	(wire
		(pts
			(xy 327.66 38.1) (xy 327.66 39.37)
		)
		(stroke
			(width 0)
			(type default)
		)
	)
	(wire
		(pts
			(xy 255.27 236.22) (xy 247.65 236.22)
		)
		(stroke
			(width 0)
			(type default)
		)
	)
	(wire
		(pts
			(xy 321.31 81.28) (xy 323.85 81.28)
		)
		(stroke
			(width 0)
			(type default)
		)
	)
	(wire
		(pts
			(xy 285.75 31.75) (xy 285.75 25.4)
		)
		(stroke
			(width 0)
			(type default)
		)
	)
	(wire
		(pts
			(xy 274.32 26.67) (xy 274.32 25.4)
		)
		(stroke
			(width 0)
			(type default)
		)
	)
	(wire
		(pts
			(xy 217.17 198.12) (xy 238.76 198.12)
		)
		(stroke
			(width 0)
			(type default)
		)
	)
	(wire
		(pts
			(xy 256.54 66.04) (xy 321.31 66.04)
		)
		(stroke
			(width 0)
			(type default)
		)
	)
	(wire
		(pts
			(xy 283.21 36.83) (xy 287.02 36.83)
		)
		(stroke
			(width 0)
			(type default)
		)
	)
	(wire
		(pts
			(xy 278.13 78.74) (xy 303.53 78.74)
		)
		(stroke
			(width 0)
			(type default)
		)
	)
	(wire
		(pts
			(xy 144.78 64.77) (xy 134.62 64.77)
		)
		(stroke
			(width 0)
			(type default)
		)
	)
	(wire
		(pts
			(xy 39.37 214.63) (xy 40.64 214.63)
		)
		(stroke
			(width 0)
			(type default)
		)
	)
	(wire
		(pts
			(xy 261.62 25.4) (xy 274.32 25.4)
		)
		(stroke
			(width 0)
			(type default)
		)
	)
	(wire
		(pts
			(xy 83.82 208.28) (xy 92.71 208.28)
		)
		(stroke
			(width 0)
			(type default)
		)
	)
	(wire
		(pts
			(xy 120.65 114.3) (xy 171.45 114.3)
		)
		(stroke
			(width 0)
			(type default)
		)
	)
	(wire
		(pts
			(xy 195.58 119.38) (xy 195.58 124.46)
		)
		(stroke
			(width 0)
			(type default)
		)
	)
	(bus
		(pts
			(xy 132.08 93.98) (xy 130.81 95.25)
		)
		(stroke
			(width 0)
			(type default)
		)
	)
	(wire
		(pts
			(xy 261.62 36.83) (xy 261.62 31.75)
		)
		(stroke
			(width 0)
			(type default)
		)
	)
	(wire
		(pts
			(xy 86.36 67.31) (xy 87.63 67.31)
		)
		(stroke
			(width 0)
			(type default)
		)
	)
	(wire
		(pts
			(xy 77.47 137.16) (xy 78.74 137.16)
		)
		(stroke
			(width 0)
			(type default)
		)
	)
	(wire
		(pts
			(xy 162.56 64.77) (xy 162.56 66.04)
		)
		(stroke
			(width 0)
			(type default)
		)
	)
	(polyline
		(pts
			(xy 12.7 165.1) (xy 407.67 165.1)
		)
		(stroke
			(width 0)
			(type default)
		)
	)
	(wire
		(pts
			(xy 30.48 254) (xy 40.64 254)
		)
		(stroke
			(width 0)
			(type default)
		)
	)
	(wire
		(pts
			(xy 140.97 215.9) (xy 149.86 215.9)
		)
		(stroke
			(width 0)
			(type default)
		)
	)
	(wire
		(pts
			(xy 250.19 25.4) (xy 261.62 25.4)
		)
		(stroke
			(width 0)
			(type default)
		)
	)
	(wire
		(pts
			(xy 170.18 229.87) (xy 170.18 227.33)
		)
		(stroke
			(width 0)
			(type default)
		)
	)
	(wire
		(pts
			(xy 45.72 105.41) (xy 45.72 106.68)
		)
		(stroke
			(width 0)
			(type default)
		)
	)
	(wire
		(pts
			(xy 270.51 118.11) (xy 270.51 119.38)
		)
		(stroke
			(width 0)
			(type default)
		)
	)
	(wire
		(pts
			(xy 261.62 25.4) (xy 261.62 26.67)
		)
		(stroke
			(width 0)
			(type default)
		)
	)
	(wire
		(pts
			(xy 217.17 218.44) (xy 228.6 218.44)
		)
		(stroke
			(width 0)
			(type default)
		)
	)
	(wire
		(pts
			(xy 339.09 210.82) (xy 328.93 210.82)
		)
		(stroke
			(width 0)
			(type default)
		)
	)
	(wire
		(pts
			(xy 260.35 236.22) (xy 266.7 236.22)
		)
		(stroke
			(width 0)
			(type default)
		)
	)
	(wire
		(pts
			(xy 146.05 185.42) (xy 146.05 191.77)
		)
		(stroke
			(width 0)
			(type default)
		)
	)
	(wire
		(pts
			(xy 237.49 227.33) (xy 237.49 247.65)
		)
		(stroke
			(width 0)
			(type default)
		)
	)
	(wire
		(pts
			(xy 195.58 104.14) (xy 195.58 101.6)
		)
		(stroke
			(width 0)
			(type default)
		)
	)
	(wire
		(pts
			(xy 347.98 39.37) (xy 347.98 38.1)
		)
		(stroke
			(width 0)
			(type default)
		)
	)
	(wire
		(pts
			(xy 217.17 257.81) (xy 242.57 257.81)
		)
		(stroke
			(width 0)
			(type default)
		)
	)
	(wire
		(pts
			(xy 162.56 101.6) (xy 167.64 101.6)
		)
		(stroke
			(width 0)
			(type default)
		)
	)
	(wire
		(pts
			(xy 260.35 231.14) (xy 266.7 231.14)
		)
		(stroke
			(width 0)
			(type default)
		)
	)
	(wire
		(pts
			(xy 280.67 81.28) (xy 306.07 81.28)
		)
		(stroke
			(width 0)
			(type default)
		)
	)
	(wire
		(pts
			(xy 240.03 217.17) (xy 242.57 217.17)
		)
		(stroke
			(width 0)
			(type default)
		)
	)
	(wire
		(pts
			(xy 318.77 205.74) (xy 339.09 205.74)
		)
		(stroke
			(width 0)
			(type default)
		)
	)
	(wire
		(pts
			(xy 73.66 72.39) (xy 73.66 71.12)
		)
		(stroke
			(width 0)
			(type default)
		)
	)
	(wire
		(pts
			(xy 300.99 73.66) (xy 300.99 101.6)
		)
		(stroke
			(width 0)
			(type default)
		)
	)
	(wire
		(pts
			(xy 120.65 95.25) (xy 120.65 102.87)
		)
		(stroke
			(width 0)
			(type default)
		)
	)
	(wire
		(pts
			(xy 256.54 73.66) (xy 300.99 73.66)
		)
		(stroke
			(width 0)
			(type default)
		)
	)
	(bus
		(pts
			(xy 88.9 231.14) (xy 88.9 233.68)
		)
		(stroke
			(width 0)
			(type default)
		)
	)
	(wire
		(pts
			(xy 181.61 260.35) (xy 179.07 260.35)
		)
		(stroke
			(width 0)
			(type default)
		)
	)
	(wire
		(pts
			(xy 97.79 203.2) (xy 113.03 203.2)
		)
		(stroke
			(width 0)
			(type default)
		)
	)
	(wire
		(pts
			(xy 50.8 99.06) (xy 71.12 99.06)
		)
		(stroke
			(width 0)
			(type default)
		)
	)
	(wire
		(pts
			(xy 302.26 36.83) (xy 303.53 36.83)
		)
		(stroke
			(width 0)
			(type default)
		)
	)
	(wire
		(pts
			(xy 138.43 185.42) (xy 138.43 191.77)
		)
		(stroke
			(width 0)
			(type default)
		)
	)
	(wire
		(pts
			(xy 199.39 123.19) (xy 199.39 124.46)
		)
		(stroke
			(width 0)
			(type default)
		)
	)
	(wire
		(pts
			(xy 303.53 36.83) (xy 303.53 41.91)
		)
		(stroke
			(width 0)
			(type default)
		)
	)
	(wire
		(pts
			(xy 194.31 104.14) (xy 195.58 104.14)
		)
		(stroke
			(width 0)
			(type default)
		)
	)
	(wire
		(pts
			(xy 30.48 256.54) (xy 55.88 256.54)
		)
		(stroke
			(width 0)
			(type default)
		)
	)
	(wire
		(pts
			(xy 74.93 99.06) (xy 74.93 100.33)
		)
		(stroke
			(width 0)
			(type default)
		)
	)
	(wire
		(pts
			(xy 109.22 111.76) (xy 109.22 114.3)
		)
		(stroke
			(width 0)
			(type default)
		)
	)
	(wire
		(pts
			(xy 170.18 99.06) (xy 171.45 99.06)
		)
		(stroke
			(width 0)
			(type default)
		)
	)
	(wire
		(pts
			(xy 245.11 222.25) (xy 245.11 217.17)
		)
		(stroke
			(width 0)
			(type default)
		)
	)
	(bus
		(pts
			(xy 88.9 236.22) (xy 88.9 238.76)
		)
		(stroke
			(width 0)
			(type default)
		)
	)
	(wire
		(pts
			(xy 302.26 34.29) (xy 306.07 34.29)
		)
		(stroke
			(width 0)
			(type default)
		)
	)
	(wire
		(pts
			(xy 109.22 111.76) (xy 171.45 111.76)
		)
		(stroke
			(width 0)
			(type default)
		)
	)
	(wire
		(pts
			(xy 83.82 200.66) (xy 92.71 200.66)
		)
		(stroke
			(width 0)
			(type default)
		)
	)
	(wire
		(pts
			(xy 360.68 205.74) (xy 358.14 205.74)
		)
		(stroke
			(width 0)
			(type default)
		)
	)
	(wire
		(pts
			(xy 83.82 205.74) (xy 92.71 205.74)
		)
		(stroke
			(width 0)
			(type default)
		)
	)
	(wire
		(pts
			(xy 109.22 116.84) (xy 109.22 119.38)
		)
		(stroke
			(width 0)
			(type default)
		)
	)
	(wire
		(pts
			(xy 86.36 99.06) (xy 86.36 105.41)
		)
		(stroke
			(width 0)
			(type default)
		)
	)
	(wire
		(pts
			(xy 113.03 116.84) (xy 171.45 116.84)
		)
		(stroke
			(width 0)
			(type default)
		)
	)
	(wire
		(pts
			(xy 86.36 128.27) (xy 97.79 128.27)
		)
		(stroke
			(width 0)
			(type default)
		)
	)
	(wire
		(pts
			(xy 217.17 212.09) (xy 233.68 212.09)
		)
		(stroke
			(width 0)
			(type default)
		)
	)
	(wire
		(pts
			(xy 242.57 217.17) (xy 245.11 217.17)
		)
		(stroke
			(width 0)
			(type default)
		)
	)
	(wire
		(pts
			(xy 347.98 31.75) (xy 347.98 33.02)
		)
		(stroke
			(width 0)
			(type default)
		)
	)
	(wire
		(pts
			(xy 217.17 232.41) (xy 247.65 232.41)
		)
		(stroke
			(width 0)
			(type default)
		)
	)
	(wire
		(pts
			(xy 278.13 78.74) (xy 278.13 107.95)
		)
		(stroke
			(width 0)
			(type default)
		)
	)
	(wire
		(pts
			(xy 97.79 208.28) (xy 113.03 208.28)
		)
		(stroke
			(width 0)
			(type default)
		)
	)
	(wire
		(pts
			(xy 60.96 237.49) (xy 87.63 237.49)
		)
		(stroke
			(width 0)
			(type default)
		)
	)
	(wire
		(pts
			(xy 271.78 231.14) (xy 276.86 231.14)
		)
		(stroke
			(width 0)
			(type default)
		)
	)
	(wire
		(pts
			(xy 26.67 203.2) (xy 26.67 204.47)
		)
		(stroke
			(width 0)
			(type default)
		)
	)
	(wire
		(pts
			(xy 153.67 71.12) (xy 153.67 72.39)
		)
		(stroke
			(width 0)
			(type default)
		)
	)
	(wire
		(pts
			(xy 179.07 260.35) (xy 179.07 262.89)
		)
		(stroke
			(width 0)
			(type default)
		)
	)
	(wire
		(pts
			(xy 120.65 107.95) (xy 120.65 114.3)
		)
		(stroke
			(width 0)
			(type default)
		)
	)
	(wire
		(pts
			(xy 232.41 237.49) (xy 217.17 237.49)
		)
		(stroke
			(width 0)
			(type default)
		)
	)
	(wire
		(pts
			(xy 270.51 110.49) (xy 280.67 110.49)
		)
		(stroke
			(width 0)
			(type default)
		)
	)
	(wire
		(pts
			(xy 339.09 210.82) (xy 339.09 213.36)
		)
		(stroke
			(width 0)
			(type default)
		)
	)
	(wire
		(pts
			(xy 308.61 71.12) (xy 323.85 71.12)
		)
		(stroke
			(width 0)
			(type default)
		)
	)
	(wire
		(pts
			(xy 359.41 219.71) (xy 359.41 218.44)
		)
		(stroke
			(width 0)
			(type default)
		)
	)
	(wire
		(pts
			(xy 217.17 234.95) (xy 247.65 234.95)
		)
		(stroke
			(width 0)
			(type default)
		)
	)
	(wire
		(pts
			(xy 285.75 242.57) (xy 280.67 242.57)
		)
		(stroke
			(width 0)
			(type default)
		)
	)
	(wire
		(pts
			(xy 247.65 231.14) (xy 255.27 231.14)
		)
		(stroke
			(width 0)
			(type default)
		)
	)
	(wire
		(pts
			(xy 224.79 66.04) (xy 223.52 66.04)
		)
		(stroke
			(width 0)
			(type default)
		)
	)
	(wire
		(pts
			(xy 318.77 208.28) (xy 336.55 208.28)
		)
		(stroke
			(width 0)
			(type default)
		)
	)
	(wire
		(pts
			(xy 72.39 214.63) (xy 78.74 214.63)
		)
		(stroke
			(width 0)
			(type default)
		)
	)
	(wire
		(pts
			(xy 287.02 31.75) (xy 285.75 31.75)
		)
		(stroke
			(width 0)
			(type default)
		)
	)
	(wire
		(pts
			(xy 209.55 62.23) (xy 209.55 63.5)
		)
		(stroke
			(width 0)
			(type default)
		)
	)
	(wire
		(pts
			(xy 86.36 144.78) (xy 86.36 146.05)
		)
		(stroke
			(width 0)
			(type default)
		)
	)
	(wire
		(pts
			(xy 179.07 260.35) (xy 179.07 257.81)
		)
		(stroke
			(width 0)
			(type default)
		)
	)
	(wire
		(pts
			(xy 71.12 99.06) (xy 74.93 99.06)
		)
		(stroke
			(width 0)
			(type default)
		)
	)
	(wire
		(pts
			(xy 234.95 227.33) (xy 234.95 245.11)
		)
		(stroke
			(width 0)
			(type default)
		)
	)
	(wire
		(pts
			(xy 162.56 72.39) (xy 162.56 71.12)
		)
		(stroke
			(width 0)
			(type default)
		)
	)
	(wire
		(pts
			(xy 90.17 99.06) (xy 90.17 105.41)
		)
		(stroke
			(width 0)
			(type default)
		)
	)
	(wire
		(pts
			(xy 223.52 74.93) (xy 223.52 69.85)
		)
		(stroke
			(width 0)
			(type default)
		)
	)
	(wire
		(pts
			(xy 199.39 114.3) (xy 207.01 114.3)
		)
		(stroke
			(width 0)
			(type default)
		)
	)
	(wire
		(pts
			(xy 276.86 231.14) (xy 276.86 236.22)
		)
		(stroke
			(width 0)
			(type default)
		)
	)
	(wire
		(pts
			(xy 109.22 119.38) (xy 171.45 119.38)
		)
		(stroke
			(width 0)
			(type default)
		)
	)
	(wire
		(pts
			(xy 134.62 64.77) (xy 134.62 66.04)
		)
		(stroke
			(width 0)
			(type default)
		)
	)
	(wire
		(pts
			(xy 328.93 201.93) (xy 328.93 210.82)
		)
		(stroke
			(width 0)
			(type default)
		)
	)
	(bus
		(pts
			(xy 281.94 246.38) (xy 283.21 245.11)
		)
		(stroke
			(width 0)
			(type default)
		)
	)
	(wire
		(pts
			(xy 60.96 240.03) (xy 87.63 240.03)
		)
		(stroke
			(width 0)
			(type default)
		)
	)
	(wire
		(pts
			(xy 163.83 218.44) (xy 170.18 218.44)
		)
		(stroke
			(width 0)
			(type default)
		)
	)
	(wire
		(pts
			(xy 149.86 207.01) (xy 149.86 208.28)
		)
		(stroke
			(width 0)
			(type default)
		)
	)
	(wire
		(pts
			(xy 261.62 250.19) (xy 280.67 250.19)
		)
		(stroke
			(width 0)
			(type default)
		)
	)
	(wire
		(pts
			(xy 97.79 120.65) (xy 106.68 120.65)
		)
		(stroke
			(width 0)
			(type default)
		)
	)
	(wire
		(pts
			(xy 163.83 229.87) (xy 170.18 229.87)
		)
		(stroke
			(width 0)
			(type default)
		)
	)
	(wire
		(pts
			(xy 153.67 196.85) (xy 153.67 198.12)
		)
		(stroke
			(width 0)
			(type default)
		)
	)
	(wire
		(pts
			(xy 71.12 99.06) (xy 71.12 111.76)
		)
		(stroke
			(width 0)
			(type default)
		)
	)
	(wire
		(pts
			(xy 303.53 78.74) (xy 322.58 78.74)
		)
		(stroke
			(width 0)
			(type default)
		)
	)
	(wire
		(pts
			(xy 321.31 132.08) (xy 321.31 129.54)
		)
		(stroke
			(width 0)
			(type default)
		)
	)
	(wire
		(pts
			(xy 306.07 41.91) (xy 306.07 40.64)
		)
		(stroke
			(width 0)
			(type default)
		)
	)
	(wire
		(pts
			(xy 39.37 201.93) (xy 39.37 204.47)
		)
		(stroke
			(width 0)
			(type default)
		)
	)
	(wire
		(pts
			(xy 318.77 218.44) (xy 339.09 218.44)
		)
		(stroke
			(width 0)
			(type default)
		)
	)
	(wire
		(pts
			(xy 264.16 107.95) (xy 275.59 107.95)
		)
		(stroke
			(width 0)
			(type default)
		)
	)
	(wire
		(pts
			(xy 30.48 259.08) (xy 55.88 259.08)
		)
		(stroke
			(width 0)
			(type default)
		)
	)
	(bus
		(pts
			(xy 90.17 229.87) (xy 88.9 231.14)
		)
		(stroke
			(width 0)
			(type default)
		)
	)
	(wire
		(pts
			(xy 73.66 207.01) (xy 73.66 219.71)
		)
		(stroke
			(width 0)
			(type default)
		)
	)
	(wire
		(pts
			(xy 73.66 207.01) (xy 72.39 207.01)
		)
		(stroke
			(width 0)
			(type default)
		)
	)
	(wire
		(pts
			(xy 39.37 209.55) (xy 39.37 214.63)
		)
		(stroke
			(width 0)
			(type default)
		)
	)
	(bus
		(pts
			(xy 285.75 245.11) (xy 283.21 245.11)
		)
		(stroke
			(width 0)
			(type default)
		)
	)
	(wire
		(pts
			(xy 306.07 81.28) (xy 306.07 101.6)
		)
		(stroke
			(width 0)
			(type default)
		)
	)
	(wire
		(pts
			(xy 107.95 64.77) (xy 113.03 64.77)
		)
		(stroke
			(width 0)
			(type default)
		)
	)
	(wire
		(pts
			(xy 50.8 119.38) (xy 50.8 120.65)
		)
		(stroke
			(width 0)
			(type default)
		)
	)
	(wire
		(pts
			(xy 153.67 64.77) (xy 153.67 66.04)
		)
		(stroke
			(width 0)
			(type default)
		)
	)
	(wire
		(pts
			(xy 217.17 193.04) (xy 238.76 193.04)
		)
		(stroke
			(width 0)
			(type default)
		)
	)
	(wire
		(pts
			(xy 223.52 66.04) (xy 223.52 54.61)
		)
		(stroke
			(width 0)
			(type default)
		)
	)
	(wire
		(pts
			(xy 97.79 120.65) (xy 97.79 121.92)
		)
		(stroke
			(width 0)
			(type default)
		)
	)
	(wire
		(pts
			(xy 180.34 193.04) (xy 180.34 185.42)
		)
		(stroke
			(width 0)
			(type default)
		)
	)
	(wire
		(pts
			(xy 83.82 203.2) (xy 92.71 203.2)
		)
		(stroke
			(width 0)
			(type default)
		)
	)
	(wire
		(pts
			(xy 237.49 217.17) (xy 234.95 217.17)
		)
		(stroke
			(width 0)
			(type default)
		)
	)
	(wire
		(pts
			(xy 138.43 196.85) (xy 138.43 198.12)
		)
		(stroke
			(width 0)
			(type default)
		)
	)
	(wire
		(pts
			(xy 242.57 227.33) (xy 242.57 257.81)
		)
		(stroke
			(width 0)
			(type default)
		)
	)
	(wire
		(pts
			(xy 251.46 257.81) (xy 242.57 257.81)
		)
		(stroke
			(width 0)
			(type default)
		)
	)
	(wire
		(pts
			(xy 35.56 116.84) (xy 50.8 116.84)
		)
		(stroke
			(width 0)
			(type default)
		)
	)
	(wire
		(pts
			(xy 195.58 64.77) (xy 195.58 99.06)
		)
		(stroke
			(width 0)
			(type default)
		)
	)
	(wire
		(pts
			(xy 274.32 34.29) (xy 287.02 34.29)
		)
		(stroke
			(width 0)
			(type default)
		)
	)
	(wire
		(pts
			(xy 217.17 247.65) (xy 237.49 247.65)
		)
		(stroke
			(width 0)
			(type default)
		)
	)
	(wire
		(pts
			(xy 217.17 200.66) (xy 260.35 200.66)
		)
		(stroke
			(width 0)
			(type default)
		)
	)
	(wire
		(pts
			(xy 146.05 185.42) (xy 180.34 185.42)
		)
		(stroke
			(width 0)
			(type default)
		)
	)
	(wire
		(pts
			(xy 314.96 34.29) (xy 306.07 34.29)
		)
		(stroke
			(width 0)
			(type default)
		)
	)
	(wire
		(pts
			(xy 170.18 101.6) (xy 171.45 101.6)
		)
		(stroke
			(width 0)
			(type default)
		)
	)
	(bus
		(pts
			(xy 130.81 95.25) (xy 130.81 97.79)
		)
		(stroke
			(width 0)
			(type default)
		)
	)
	(wire
		(pts
			(xy 161.29 190.5) (xy 175.26 190.5)
		)
		(stroke
			(width 0)
			(type default)
		)
	)
	(wire
		(pts
			(xy 306.07 41.91) (xy 306.07 44.45)
		)
		(stroke
			(width 0)
			(type default)
		)
	)
	(wire
		(pts
			(xy 247.65 236.22) (xy 247.65 234.95)
		)
		(stroke
			(width 0)
			(type default)
		)
	)
	(wire
		(pts
			(xy 275.59 107.95) (xy 278.13 107.95)
		)
		(stroke
			(width 0)
			(type default)
		)
	)
	(bus
		(pts
			(xy 86.36 251.46) (xy 83.82 251.46)
		)
		(stroke
			(width 0)
			(type default)
		)
	)
	(wire
		(pts
			(xy 161.29 191.77) (xy 161.29 190.5)
		)
		(stroke
			(width 0)
			(type default)
		)
	)
	(wire
		(pts
			(xy 306.07 34.29) (xy 306.07 35.56)
		)
		(stroke
			(width 0)
			(type default)
		)
	)
	(wire
		(pts
			(xy 86.36 116.84) (xy 71.12 116.84)
		)
		(stroke
			(width 0)
			(type default)
		)
	)
	(wire
		(pts
			(xy 97.79 205.74) (xy 113.03 205.74)
		)
		(stroke
			(width 0)
			(type default)
		)
	)
	(wire
		(pts
			(xy 86.36 119.38) (xy 71.12 119.38)
		)
		(stroke
			(width 0)
			(type default)
		)
	)
	(wire
		(pts
			(xy 181.61 193.04) (xy 180.34 193.04)
		)
		(stroke
			(width 0)
			(type default)
		)
	)
	(wire
		(pts
			(xy 364.49 201.93) (xy 364.49 203.2)
		)
		(stroke
			(width 0)
			(type default)
		)
	)
	(wire
		(pts
			(xy 45.72 99.06) (xy 45.72 100.33)
		)
		(stroke
			(width 0)
			(type default)
		)
	)
	(wire
		(pts
			(xy 69.85 256.54) (xy 81.28 256.54)
		)
		(stroke
			(width 0)
			(type default)
		)
	)
	(wire
		(pts
			(xy 360.68 194.31) (xy 364.49 194.31)
		)
		(stroke
			(width 0)
			(type default)
		)
	)
	(wire
		(pts
			(xy 274.32 25.4) (xy 285.75 25.4)
		)
		(stroke
			(width 0)
			(type default)
		)
	)
	(bus
		(pts
			(xy 133.35 93.98) (xy 132.08 93.98)
		)
		(stroke
			(width 0)
			(type default)
		)
	)
	(wire
		(pts
			(xy 261.62 43.18) (xy 246.38 43.18)
		)
		(stroke
			(width 0)
			(type default)
		)
	)
	(wire
		(pts
			(xy 321.31 81.28) (xy 321.31 86.36)
		)
		(stroke
			(width 0)
			(type default)
		)
	)
	(wire
		(pts
			(xy 328.93 194.31) (xy 346.71 194.31)
		)
		(stroke
			(width 0)
			(type default)
		)
	)
	(wire
		(pts
			(xy 179.07 257.81) (xy 181.61 257.81)
		)
		(stroke
			(width 0)
			(type default)
		)
	)
	(wire
		(pts
			(xy 209.55 54.61) (xy 209.55 57.15)
		)
		(stroke
			(width 0)
			(type default)
		)
	)
	(polyline
		(pts
			(xy 116.84 284.48) (xy 116.84 170.18)
		)
		(stroke
			(width 0)
			(type default)
		)
	)
	(wire
		(pts
			(xy 86.36 67.31) (xy 86.36 64.77)
		)
		(stroke
			(width 0)
			(type default)
		)
	)
	(wire
		(pts
			(xy 60.96 232.41) (xy 87.63 232.41)
		)
		(stroke
			(width 0)
			(type default)
		)
	)
	(wire
		(pts
			(xy 234.95 245.11) (xy 256.54 245.11)
		)
		(stroke
			(width 0)
			(type default)
		)
	)
	(wire
		(pts
			(xy 217.17 260.35) (xy 245.11 260.35)
		)
		(stroke
			(width 0)
			(type default)
		)
	)
	(bus
		(pts
			(xy 281.94 246.38) (xy 281.94 248.92)
		)
		(stroke
			(width 0)
			(type default)
		)
	)
	(wire
		(pts
			(xy 97.79 128.27) (xy 97.79 129.54)
		)
		(stroke
			(width 0)
			(type default)
		)
	)
	(wire
		(pts
			(xy 195.58 101.6) (xy 195.58 99.06)
		)
		(stroke
			(width 0)
			(type default)
		)
	)
	(wire
		(pts
			(xy 293.37 101.6) (xy 298.45 101.6)
		)
		(stroke
			(width 0)
			(type default)
		)
	)
	(wire
		(pts
			(xy 26.67 204.47) (xy 39.37 204.47)
		)
		(stroke
			(width 0)
			(type default)
		)
	)
	(wire
		(pts
			(xy 109.22 116.84) (xy 86.36 116.84)
		)
		(stroke
			(width 0)
			(type default)
		)
	)
	(wire
		(pts
			(xy 44.45 240.03) (xy 55.88 240.03)
		)
		(stroke
			(width 0)
			(type default)
		)
	)
	(wire
		(pts
			(xy 44.45 234.95) (xy 55.88 234.95)
		)
		(stroke
			(width 0)
			(type default)
		)
	)
	(wire
		(pts
			(xy 149.86 215.9) (xy 149.86 227.33)
		)
		(stroke
			(width 0)
			(type default)
		)
	)
	(wire
		(pts
			(xy 311.15 209.55) (xy 311.15 210.82)
		)
		(stroke
			(width 0)
			(type default)
		)
	)
	(wire
		(pts
			(xy 318.77 215.9) (xy 339.09 215.9)
		)
		(stroke
			(width 0)
			(type default)
		)
	)
	(wire
		(pts
			(xy 303.53 41.91) (xy 306.07 41.91)
		)
		(stroke
			(width 0)
			(type default)
		)
	)
	(wire
		(pts
			(xy 199.39 114.3) (xy 199.39 118.11)
		)
		(stroke
			(width 0)
			(type default)
		)
	)
	(wire
		(pts
			(xy 358.14 218.44) (xy 359.41 218.44)
		)
		(stroke
			(width 0)
			(type default)
		)
	)
	(wire
		(pts
			(xy 116.84 137.16) (xy 104.14 137.16)
		)
		(stroke
			(width 0)
			(type default)
		)
	)
	(wire
		(pts
			(xy 113.03 107.95) (xy 113.03 116.84)
		)
		(stroke
			(width 0)
			(type default)
		)
	)
	(wire
		(pts
			(xy 242.57 217.17) (xy 242.57 222.25)
		)
		(stroke
			(width 0)
			(type default)
		)
	)
	(wire
		(pts
			(xy 322.58 78.74) (xy 323.85 78.74)
		)
		(stroke
			(width 0)
			(type default)
		)
	)
	(wire
		(pts
			(xy 34.29 212.09) (xy 40.64 212.09)
		)
		(stroke
			(width 0)
			(type default)
		)
	)
	(wire
		(pts
			(xy 300.99 73.66) (xy 323.85 73.66)
		)
		(stroke
			(width 0)
			(type default)
		)
	)
	(bus
		(pts
			(xy 130.81 97.79) (xy 130.81 100.33)
		)
		(stroke
			(width 0)
			(type default)
		)
	)
	(wire
		(pts
			(xy 181.61 198.12) (xy 175.26 198.12)
		)
		(stroke
			(width 0)
			(type default)
		)
	)
	(wire
		(pts
			(xy 175.26 198.12) (xy 175.26 190.5)
		)
		(stroke
			(width 0)
			(type default)
		)
	)
	(wire
		(pts
			(xy 306.07 81.28) (xy 321.31 81.28)
		)
		(stroke
			(width 0)
			(type default)
		)
	)
	(wire
		(pts
			(xy 323.85 83.82) (xy 322.58 83.82)
		)
		(stroke
			(width 0)
			(type default)
		)
	)
	(wire
		(pts
			(xy 347.98 31.75) (xy 359.41 31.75)
		)
		(stroke
			(width 0)
			(type default)
		)
	)
	(wire
		(pts
			(xy 199.39 114.3) (xy 194.31 114.3)
		)
		(stroke
			(width 0)
			(type default)
		)
	)
	(wire
		(pts
			(xy 45.72 254) (xy 55.88 254)
		)
		(stroke
			(width 0)
			(type default)
		)
	)
	(wire
		(pts
			(xy 170.18 215.9) (xy 170.18 218.44)
		)
		(stroke
			(width 0)
			(type default)
		)
	)
	(wire
		(pts
			(xy 97.79 200.66) (xy 113.03 200.66)
		)
		(stroke
			(width 0)
			(type default)
		)
	)
	(wire
		(pts
			(xy 35.56 114.3) (xy 50.8 114.3)
		)
		(stroke
			(width 0)
			(type default)
		)
	)
	(wire
		(pts
			(xy 240.03 217.17) (xy 237.49 217.17)
		)
		(stroke
			(width 0)
			(type default)
		)
	)
	(wire
		(pts
			(xy 223.52 69.85) (xy 224.79 69.85)
		)
		(stroke
			(width 0)
			(type default)
		)
	)
	(wire
		(pts
			(xy 217.17 245.11) (xy 234.95 245.11)
		)
		(stroke
			(width 0)
			(type default)
		)
	)
	(bus
		(pts
			(xy 88.9 233.68) (xy 88.9 236.22)
		)
		(stroke
			(width 0)
			(type default)
		)
	)
	(wire
		(pts
			(xy 120.65 64.77) (xy 134.62 64.77)
		)
		(stroke
			(width 0)
			(type default)
		)
	)
	(wire
		(pts
			(xy 275.59 107.95) (xy 275.59 113.03)
		)
		(stroke
			(width 0)
			(type default)
		)
	)
	(wire
		(pts
			(xy 337.82 31.75) (xy 337.82 33.02)
		)
		(stroke
			(width 0)
			(type default)
		)
	)
	(wire
		(pts
			(xy 217.17 250.19) (xy 240.03 250.19)
		)
		(stroke
			(width 0)
			(type default)
		)
	)
	(wire
		(pts
			(xy 321.31 31.75) (xy 327.66 31.75)
		)
		(stroke
			(width 0)
			(type default)
		)
	)
	(wire
		(pts
			(xy 321.31 66.04) (xy 323.85 66.04)
		)
		(stroke
			(width 0)
			(type default)
		)
	)
	(wire
		(pts
			(xy 86.36 129.54) (xy 86.36 128.27)
		)
		(stroke
			(width 0)
			(type default)
		)
	)
	(wire
		(pts
			(xy 109.22 67.31) (xy 109.22 72.39)
		)
		(stroke
			(width 0)
			(type default)
		)
	)
	(wire
		(pts
			(xy 209.55 54.61) (xy 214.63 54.61)
		)
		(stroke
			(width 0)
			(type default)
		)
	)
	(wire
		(pts
			(xy 214.63 54.61) (xy 214.63 57.15)
		)
		(stroke
			(width 0)
			(type default)
		)
	)
	(wire
		(pts
			(xy 95.25 99.06) (xy 90.17 99.06)
		)
		(stroke
			(width 0)
			(type default)
		)
	)
	(wire
		(pts
			(xy 217.17 223.52) (xy 228.6 223.52)
		)
		(stroke
			(width 0)
			(type default)
		)
	)
	(wire
		(pts
			(xy 50.8 99.06) (xy 50.8 111.76)
		)
		(stroke
			(width 0)
			(type default)
		)
	)
	(wire
		(pts
			(xy 97.79 127) (xy 97.79 128.27)
		)
		(stroke
			(width 0)
			(type default)
		)
	)
	(wire
		(pts
			(xy 109.22 114.3) (xy 90.17 114.3)
		)
		(stroke
			(width 0)
			(type default)
		)
	)
	(wire
		(pts
			(xy 245.11 227.33) (xy 245.11 260.35)
		)
		(stroke
			(width 0)
			(type default)
		)
	)
	(wire
		(pts
			(xy 234.95 217.17) (xy 234.95 222.25)
		)
		(stroke
			(width 0)
			(type default)
		)
	)
	(wire
		(pts
			(xy 90.17 114.3) (xy 71.12 114.3)
		)
		(stroke
			(width 0)
			(type default)
		)
	)
	(wire
		(pts
			(xy 73.66 64.77) (xy 86.36 64.77)
		)
		(stroke
			(width 0)
			(type default)
		)
	)
	(wire
		(pts
			(xy 86.36 110.49) (xy 86.36 116.84)
		)
		(stroke
			(width 0)
			(type default)
		)
	)
	(wire
		(pts
			(xy 336.55 201.93) (xy 336.55 208.28)
		)
		(stroke
			(width 0)
			(type default)
		)
	)
	(polyline
		(pts
			(xy 116.84 165.1) (xy 116.84 170.18)
		)
		(stroke
			(width 0)
			(type default)
		)
	)
	(wire
		(pts
			(xy 120.65 64.77) (xy 120.65 90.17)
		)
		(stroke
			(width 0)
			(type default)
		)
	)
	(wire
		(pts
			(xy 335.28 201.93) (xy 336.55 201.93)
		)
		(stroke
			(width 0)
			(type default)
		)
	)
	(wire
		(pts
			(xy 132.08 101.6) (xy 157.48 101.6)
		)
		(stroke
			(width 0)
			(type default)
		)
	)
	(wire
		(pts
			(xy 271.78 34.29) (xy 274.32 34.29)
		)
		(stroke
			(width 0)
			(type default)
		)
	)
	(wire
		(pts
			(xy 303.53 78.74) (xy 303.53 101.6)
		)
		(stroke
			(width 0)
			(type default)
		)
	)
	(wire
		(pts
			(xy 50.8 99.06) (xy 45.72 99.06)
		)
		(stroke
			(width 0)
			(type default)
		)
	)
	(wire
		(pts
			(xy 153.67 187.96) (xy 177.8 187.96)
		)
		(stroke
			(width 0)
			(type default)
		)
	)
	(wire
		(pts
			(xy 237.49 217.17) (xy 237.49 222.25)
		)
		(stroke
			(width 0)
			(type default)
		)
	)
	(wire
		(pts
			(xy 280.67 81.28) (xy 280.67 110.49)
		)
		(stroke
			(width 0)
			(type default)
		)
	)
	(wire
		(pts
			(xy 264.16 110.49) (xy 270.51 110.49)
		)
		(stroke
			(width 0)
			(type default)
		)
	)
	(wire
		(pts
			(xy 153.67 229.87) (xy 158.75 229.87)
		)
		(stroke
			(width 0)
			(type default)
		)
	)
	(wire
		(pts
			(xy 194.31 119.38) (xy 195.58 119.38)
		)
		(stroke
			(width 0)
			(type default)
		)
	)
	(wire
		(pts
			(xy 321.31 129.54) (xy 323.85 129.54)
		)
		(stroke
			(width 0)
			(type default)
		)
	)
	(wire
		(pts
			(xy 280.67 242.57) (xy 280.67 245.11)
		)
		(stroke
			(width 0)
			(type default)
		)
	)
	(wire
		(pts
			(xy 86.36 139.7) (xy 86.36 144.78)
		)
		(stroke
			(width 0)
			(type default)
		)
	)
	(wire
		(pts
			(xy 240.03 227.33) (xy 240.03 250.19)
		)
		(stroke
			(width 0)
			(type default)
		)
	)
	(wire
		(pts
			(xy 153.67 218.44) (xy 158.75 218.44)
		)
		(stroke
			(width 0)
			(type default)
		)
	)
	(wire
		(pts
			(xy 78.74 143.51) (xy 78.74 144.78)
		)
		(stroke
			(width 0)
			(type default)
		)
	)
	(wire
		(pts
			(xy 138.43 182.88) (xy 138.43 185.42)
		)
		(stroke
			(width 0)
			(type default)
		)
	)
	(wire
		(pts
			(xy 237.49 247.65) (xy 256.54 247.65)
		)
		(stroke
			(width 0)
			(type default)
		)
	)
	(wire
		(pts
			(xy 217.17 220.98) (xy 228.6 220.98)
		)
		(stroke
			(width 0)
			(type default)
		)
	)
	(wire
		(pts
			(xy 321.31 132.08) (xy 323.85 132.08)
		)
		(stroke
			(width 0)
			(type default)
		)
	)
	(wire
		(pts
			(xy 308.61 71.12) (xy 308.61 101.6)
		)
		(stroke
			(width 0)
			(type default)
		)
	)
	(wire
		(pts
			(xy 261.62 245.11) (xy 280.67 245.11)
		)
		(stroke
			(width 0)
			(type default)
		)
	)
	(wire
		(pts
			(xy 74.93 105.41) (xy 74.93 106.68)
		)
		(stroke
			(width 0)
			(type default)
		)
	)
	(wire
		(pts
			(xy 214.63 81.28) (xy 214.63 82.55)
		)
		(stroke
			(width 0)
			(type default)
		)
	)
	(wire
		(pts
			(xy 359.41 44.45) (xy 359.41 45.72)
		)
		(stroke
			(width 0)
			(type default)
		)
	)
	(wire
		(pts
			(xy 194.31 110.49) (xy 259.08 110.49)
		)
		(stroke
			(width 0)
			(type default)
		)
	)
	(wire
		(pts
			(xy 134.62 63.5) (xy 134.62 64.77)
		)
		(stroke
			(width 0)
			(type default)
		)
	)
	(wire
		(pts
			(xy 149.86 207.01) (xy 158.75 207.01)
		)
		(stroke
			(width 0)
			(type default)
		)
	)
	(wire
		(pts
			(xy 163.83 227.33) (xy 170.18 227.33)
		)
		(stroke
			(width 0)
			(type default)
		)
	)
	(wire
		(pts
			(xy 60.96 256.54) (xy 69.85 256.54)
		)
		(stroke
			(width 0)
			(type default)
		)
	)
	(wire
		(pts
			(xy 250.19 25.4) (xy 250.19 26.67)
		)
		(stroke
			(width 0)
			(type default)
		)
	)
	(bus
		(pts
			(xy 92.71 229.87) (xy 90.17 229.87)
		)
		(stroke
			(width 0)
			(type default)
		)
	)
	(wire
		(pts
			(xy 162.56 64.77) (xy 195.58 64.77)
		)
		(stroke
			(width 0)
			(type default)
		)
	)
	(wire
		(pts
			(xy 60.96 259.08) (xy 69.85 259.08)
		)
		(stroke
			(width 0)
			(type default)
		)
	)
	(wire
		(pts
			(xy 336.55 208.28) (xy 339.09 208.28)
		)
		(stroke
			(width 0)
			(type default)
		)
	)
	(wire
		(pts
			(xy 78.74 144.78) (xy 86.36 144.78)
		)
		(stroke
			(width 0)
			(type default)
		)
	)
	(wire
		(pts
			(xy 113.03 64.77) (xy 113.03 90.17)
		)
		(stroke
			(width 0)
			(type default)
		)
	)
	(wire
		(pts
			(xy 146.05 196.85) (xy 146.05 198.12)
		)
		(stroke
			(width 0)
			(type default)
		)
	)
	(wire
		(pts
			(xy 134.62 72.39) (xy 134.62 71.12)
		)
		(stroke
			(width 0)
			(type default)
		)
	)
	(wire
		(pts
			(xy 144.78 64.77) (xy 144.78 66.04)
		)
		(stroke
			(width 0)
			(type default)
		)
	)
	(wire
		(pts
			(xy 256.54 71.12) (xy 308.61 71.12)
		)
		(stroke
			(width 0)
			(type default)
		)
	)
	(wire
		(pts
			(xy 337.82 38.1) (xy 337.82 39.37)
		)
		(stroke
			(width 0)
			(type default)
		)
	)
	(wire
		(pts
			(xy 337.82 31.75) (xy 347.98 31.75)
		)
		(stroke
			(width 0)
			(type default)
		)
	)
	(wire
		(pts
			(xy 163.83 215.9) (xy 170.18 215.9)
		)
		(stroke
			(width 0)
			(type default)
		)
	)
	(wire
		(pts
			(xy 149.86 215.9) (xy 158.75 215.9)
		)
		(stroke
			(width 0)
			(type default)
		)
	)
	(wire
		(pts
			(xy 214.63 62.23) (xy 214.63 63.5)
		)
		(stroke
			(width 0)
			(type default)
		)
	)
	(wire
		(pts
			(xy 322.58 78.74) (xy 322.58 83.82)
		)
		(stroke
			(width 0)
			(type default)
		)
	)
	(wire
		(pts
			(xy 44.45 237.49) (xy 55.88 237.49)
		)
		(stroke
			(width 0)
			(type default)
		)
	)
	(wire
		(pts
			(xy 311.15 210.82) (xy 328.93 210.82)
		)
		(stroke
			(width 0)
			(type default)
		)
	)
	(wire
		(pts
			(xy 360.68 194.31) (xy 360.68 205.74)
		)
		(stroke
			(width 0)
			(type default)
		)
	)
	(wire
		(pts
			(xy 78.74 137.16) (xy 78.74 138.43)
		)
		(stroke
			(width 0)
			(type default)
		)
	)
	(wire
		(pts
			(xy 113.03 64.77) (xy 120.65 64.77)
		)
		(stroke
			(width 0)
			(type default)
		)
	)
	(wire
		(pts
			(xy 44.45 232.41) (xy 55.88 232.41)
		)
		(stroke
			(width 0)
			(type default)
		)
	)
	(wire
		(pts
			(xy 217.17 203.2) (xy 236.22 203.2)
		)
		(stroke
			(width 0)
			(type default)
		)
	)
	(wire
		(pts
			(xy 327.66 31.75) (xy 337.82 31.75)
		)
		(stroke
			(width 0)
			(type default)
		)
	)
	(wire
		(pts
			(xy 323.85 86.36) (xy 321.31 86.36)
		)
		(stroke
			(width 0)
			(type default)
		)
	)
	(wire
		(pts
			(xy 327.66 31.75) (xy 327.66 33.02)
		)
		(stroke
			(width 0)
			(type default)
		)
	)
	(wire
		(pts
			(xy 72.39 209.55) (xy 78.74 209.55)
		)
		(stroke
			(width 0)
			(type default)
		)
	)
	(wire
		(pts
			(xy 73.66 64.77) (xy 73.66 66.04)
		)
		(stroke
			(width 0)
			(type default)
		)
	)
	(wire
		(pts
			(xy 293.37 101.6) (xy 293.37 102.87)
		)
		(stroke
			(width 0)
			(type default)
		)
	)
	(wire
		(pts
			(xy 275.59 118.11) (xy 275.59 119.38)
		)
		(stroke
			(width 0)
			(type default)
		)
	)
	(wire
		(pts
			(xy 149.86 227.33) (xy 158.75 227.33)
		)
		(stroke
			(width 0)
			(type default)
		)
	)
	(wire
		(pts
			(xy 217.17 195.58) (xy 238.76 195.58)
		)
		(stroke
			(width 0)
			(type default)
		)
	)
	(wire
		(pts
			(xy 170.18 99.06) (xy 167.64 101.6)
		)
		(stroke
			(width 0)
			(type default)
		)
	)
	(wire
		(pts
			(xy 132.08 99.06) (xy 157.48 99.06)
		)
		(stroke
			(width 0)
			(type default)
		)
	)
	(wire
		(pts
			(xy 39.37 204.47) (xy 40.64 204.47)
		)
		(stroke
			(width 0)
			(type default)
		)
	)
	(wire
		(pts
			(xy 60.96 254) (xy 81.28 254)
		)
		(stroke
			(width 0)
			(type default)
		)
	)
	(wire
		(pts
			(xy 144.78 72.39) (xy 144.78 71.12)
		)
		(stroke
			(width 0)
			(type default)
		)
	)
	(wire
		(pts
			(xy 261.62 36.83) (xy 274.32 36.83)
		)
		(stroke
			(width 0)
			(type default)
		)
	)
	(wire
		(pts
			(xy 78.74 137.16) (xy 80.01 137.16)
		)
		(stroke
			(width 0)
			(type default)
		)
	)
	(wire
		(pts
			(xy 217.17 215.9) (xy 228.6 215.9)
		)
		(stroke
			(width 0)
			(type default)
		)
	)
	(label "PDC_I2C2_SCL"
		(at 218.44 257.81 0)
		(effects
			(font
				(size 1.27 1.27)
			)
			(justify left bottom)
		)
	)
	(label "~{PDC_CS}"
		(at 318.77 218.44 0)
		(effects
			(font
				(size 1.27 1.27)
			)
			(justify left bottom)
		)
	)
	(label "PDC_SCLK"
		(at 228.6 220.98 180)
		(effects
			(font
				(size 1.27 1.27)
			)
			(justify right bottom)
		)
	)
	(label "MOSI"
		(at 78.74 209.55 180)
		(effects
			(font
				(size 1.27 1.27)
			)
			(justify right bottom)
		)
	)
	(label "SPI_{HUB_DEBUG}.SCK"
		(at 67.31 237.49 0)
		(effects
			(font
				(size 1.27 1.27)
			)
			(justify left bottom)
		)
	)
	(label "SCK"
		(at 83.82 205.74 0)
		(effects
			(font
				(size 1.27 1.27)
			)
			(justify left bottom)
		)
	)
	(label "FTDI_LED_RX"
		(at 158.75 114.3 0)
		(effects
			(font
				(size 1.27 1.27)
			)
			(justify left bottom)
		)
	)
	(label "PDC_SCLK"
		(at 318.77 215.9 0)
		(effects
			(font
				(size 1.27 1.27)
			)
			(justify left bottom)
		)
	)
	(label "PDC_MOSI"
		(at 228.6 218.44 180)
		(effects
			(font
				(size 1.27 1.27)
			)
			(justify right bottom)
		)
	)
	(label "SCK"
		(at 44.45 237.49 0)
		(effects
			(font
				(size 1.27 1.27)
			)
			(justify left bottom)
		)
	)
	(label "PDC_I2C3_SCL"
		(at 218.44 207.01 0)
		(effects
			(font
				(size 1.27 1.27)
			)
			(justify left bottom)
		)
	)
	(label "PDC_MOSI"
		(at 318.77 205.74 0)
		(effects
			(font
				(size 1.27 1.27)
			)
			(justify left bottom)
		)
	)
	(label "DEBUG_SCL"
		(at 218.44 247.65 0)
		(effects
			(font
				(size 1.27 1.27)
			)
			(justify left bottom)
		)
	)
	(label "I2C_{SYS}.SDA"
		(at 267.97 250.19 0)
		(effects
			(font
				(size 1.27 1.27)
			)
			(justify left bottom)
		)
	)
	(label "FTDI_3V3"
		(at 106.68 120.65 180)
		(effects
			(font
				(size 1.27 1.27)
			)
			(justify right bottom)
		)
	)
	(label "PDC_LDO_3V3"
		(at 173.99 190.5 180)
		(effects
			(font
				(size 1.27 1.27)
			)
			(justify right bottom)
		)
	)
	(label "FTDI_3V3"
		(at 227.33 114.3 180)
		(effects
			(font
				(size 1.27 1.27)
			)
			(justify right bottom)
		)
	)
	(label "USB_FTDI_P"
		(at 209.55 107.95 180)
		(effects
			(font
				(size 1.27 1.27)
			)
			(justify right bottom)
		)
	)
	(label "FTDI_LED_RX"
		(at 116.84 137.16 180)
		(effects
			(font
				(size 1.27 1.27)
			)
			(justify right bottom)
		)
	)
	(label "PDC_MISO"
		(at 318.77 208.28 0)
		(effects
			(font
				(size 1.27 1.27)
			)
			(justify left bottom)
		)
	)
	(label "USB_FTDI_N"
		(at 209.55 110.49 180)
		(effects
			(font
				(size 1.27 1.27)
			)
			(justify right bottom)
		)
	)
	(label "USBC0_5V_PEN"
		(at 232.41 237.49 180)
		(effects
			(font
				(size 1.27 1.27)
			)
			(justify right bottom)
		)
	)
	(label "SCK"
		(at 34.29 212.09 0)
		(effects
			(font
				(size 1.27 1.27)
			)
			(justify left bottom)
		)
	)
	(label "MOSI"
		(at 44.45 234.95 0)
		(effects
			(font
				(size 1.27 1.27)
			)
			(justify left bottom)
		)
	)
	(label "DEBUG_SDA"
		(at 218.44 250.19 0)
		(effects
			(font
				(size 1.27 1.27)
			)
			(justify left bottom)
		)
	)
	(label "PDC_HPD2"
		(at 228.6 203.2 180)
		(effects
			(font
				(size 1.27 1.27)
			)
			(justify right bottom)
		)
	)
	(label "USBC0_VBUS"
		(at 73.66 64.77 0)
		(effects
			(font
				(size 1.27 1.27)
			)
			(justify left bottom)
		)
	)
	(label "SPI_{HUB_DEBUG}.MOSI"
		(at 67.31 234.95 0)
		(effects
			(font
				(size 1.27 1.27)
			)
			(justify left bottom)
		)
	)
	(label "~{PDC_I2C3_IRQ}"
		(at 218.44 212.09 0)
		(effects
			(font
				(size 1.27 1.27)
			)
			(justify left bottom)
		)
	)
	(label "MISO"
		(at 44.45 240.03 0)
		(effects
			(font
				(size 1.27 1.27)
			)
			(justify left bottom)
		)
	)
	(label "UART3_DEBUG.RX"
		(at 134.62 101.6 0)
		(effects
			(font
				(size 1.27 1.27)
			)
			(justify left bottom)
		)
	)
	(label "FTDI_LED_TX"
		(at 158.75 116.84 0)
		(effects
			(font
				(size 1.27 1.27)
			)
			(justify left bottom)
		)
	)
	(label "~{CS}"
		(at 83.82 200.66 0)
		(effects
			(font
				(size 1.27 1.27)
			)
			(justify left bottom)
		)
	)
	(label "SPI_{HUB_DEBUG}.MISO"
		(at 67.31 240.03 0)
		(effects
			(font
				(size 1.27 1.27)
			)
			(justify left bottom)
		)
	)
	(label "USBC0_FLG"
		(at 275.59 34.29 0)
		(effects
			(font
				(size 1.27 1.27)
			)
			(justify left bottom)
		)
	)
	(label "I2C_{SYS}.SCL"
		(at 80.01 254 180)
		(effects
			(font
				(size 1.27 1.27)
			)
			(justify right bottom)
		)
	)
	(label "PDC_I2C1_IRQn"
		(at 218.44 245.11 0)
		(effects
			(font
				(size 1.27 1.27)
			)
			(justify left bottom)
		)
	)
	(label "SPI_{HUB_DEBUG}.~{CS0}"
		(at 67.31 232.41 0)
		(effects
			(font
				(size 1.27 1.27)
			)
			(justify left bottom)
		)
	)
	(label "MOSI"
		(at 83.82 203.2 0)
		(effects
			(font
				(size 1.27 1.27)
			)
			(justify left bottom)
		)
	)
	(label "PDC_I2C2_IRQn"
		(at 218.44 255.27 0)
		(effects
			(font
				(size 1.27 1.27)
			)
			(justify left bottom)
		)
	)
	(label "SCK"
		(at 30.48 254 0)
		(effects
			(font
				(size 1.27 1.27)
			)
			(justify left bottom)
		)
	)
	(label "PDC_MISO"
		(at 228.6 215.9 180)
		(effects
			(font
				(size 1.27 1.27)
			)
			(justify right bottom)
		)
	)
	(label "USBC0_CC1"
		(at 260.35 71.12 0)
		(effects
			(font
				(size 1.27 1.27)
			)
			(justify left bottom)
		)
	)
	(label "I2C_{SYS}.SCL"
		(at 267.97 247.65 0)
		(effects
			(font
				(size 1.27 1.27)
			)
			(justify left bottom)
		)
	)
	(label "FTDI_CBUS0{slash}SDA"
		(at 91.44 114.3 0)
		(effects
			(font
				(size 1.27 1.27)
			)
			(justify left bottom)
		)
	)
	(label "PDC_ADCIN1"
		(at 168.91 215.9 0)
		(effects
			(font
				(size 1.27 1.27)
			)
			(justify left bottom)
		)
	)
	(label "PDC_GPIO14"
		(at 229.87 232.41 180)
		(effects
			(font
				(size 1.27 1.27)
			)
			(justify right bottom)
		)
	)
	(label "PDC_SCLK"
		(at 113.03 205.74 180)
		(effects
			(font
				(size 1.27 1.27)
			)
			(justify right bottom)
		)
	)
	(label "FTDI_3V3"
		(at 62.23 99.06 0)
		(effects
			(font
				(size 1.27 1.27)
			)
			(justify left bottom)
		)
	)
	(label "MOSI"
		(at 30.48 259.08 0)
		(effects
			(font
				(size 1.27 1.27)
			)
			(justify left bottom)
		)
	)
	(label "DEBUG_SCL"
		(at 35.56 116.84 0)
		(effects
			(font
				(size 1.27 1.27)
			)
			(justify left bottom)
		)
	)
	(label "PDC_LDO_3V3"
		(at 140.97 215.9 0)
		(effects
			(font
				(size 1.27 1.27)
			)
			(justify left bottom)
		)
	)
	(label "FTDI_3V3"
		(at 120.65 64.77 180)
		(effects
			(font
				(size 1.27 1.27)
			)
			(justify right bottom)
		)
	)
	(label "FTDI_3V3"
		(at 95.25 99.06 180)
		(effects
			(font
				(size 1.27 1.27)
			)
			(justify right bottom)
		)
	)
	(label "~{PDC_CS}"
		(at 228.6 223.52 180)
		(effects
			(font
				(size 1.27 1.27)
			)
			(justify right bottom)
		)
	)
	(label "PDC_I2C2_SDA"
		(at 218.44 260.35 0)
		(effects
			(font
				(size 1.27 1.27)
			)
			(justify left bottom)
		)
	)
	(label "MISO"
		(at 30.48 256.54 0)
		(effects
			(font
				(size 1.27 1.27)
			)
			(justify left bottom)
		)
	)
	(label "USBC0_5V_PEN"
		(at 246.38 43.18 0)
		(effects
			(font
				(size 1.27 1.27)
			)
			(justify left bottom)
		)
	)
	(label "MISO"
		(at 83.82 208.28 0)
		(effects
			(font
				(size 1.27 1.27)
			)
			(justify left bottom)
		)
	)
	(label "DEBUG_SDA"
		(at 35.56 114.3 0)
		(effects
			(font
				(size 1.27 1.27)
			)
			(justify left bottom)
		)
	)
	(label "USBC0_VBUS"
		(at 260.35 66.04 0)
		(effects
			(font
				(size 1.27 1.27)
			)
			(justify left bottom)
		)
	)
	(label "PDC_MISO"
		(at 113.03 208.28 180)
		(effects
			(font
				(size 1.27 1.27)
			)
			(justify right bottom)
		)
	)
	(label "UART3_DEBUG.TX"
		(at 134.62 99.06 0)
		(effects
			(font
				(size 1.27 1.27)
			)
			(justify left bottom)
		)
	)
	(label "PDC_I2C3_SDA"
		(at 218.44 209.55 0)
		(effects
			(font
				(size 1.27 1.27)
			)
			(justify left bottom)
		)
	)
	(label "USBC0_D_N"
		(at 309.88 81.28 0)
		(effects
			(font
				(size 1.27 1.27)
			)
			(justify left bottom)
		)
	)
	(label "USBC0_D_P"
		(at 309.88 78.74 0)
		(effects
			(font
				(size 1.27 1.27)
			)
			(justify left bottom)
		)
	)
	(label "USBC0_CC2"
		(at 260.35 73.66 0)
		(effects
			(font
				(size 1.27 1.27)
			)
			(justify left bottom)
		)
	)
	(label "FTDI_CBUS_EN"
		(at 85.09 119.38 180)
		(effects
			(font
				(size 1.27 1.27)
			)
			(justify right bottom)
		)
	)
	(label "PDC_RESET"
		(at 168.91 207.01 0)
		(effects
			(font
				(size 1.27 1.27)
			)
			(justify left bottom)
		)
	)
	(label "PDC_ADCIN2"
		(at 168.91 227.33 0)
		(effects
			(font
				(size 1.27 1.27)
			)
			(justify left bottom)
		)
	)
	(label "~{CS}"
		(at 34.29 207.01 0)
		(effects
			(font
				(size 1.27 1.27)
			)
			(justify left bottom)
		)
	)
	(label "~{PDC_CS}"
		(at 113.03 200.66 180)
		(effects
			(font
				(size 1.27 1.27)
			)
			(justify right bottom)
		)
	)
	(label "I2C_{SYS}.SDA"
		(at 80.01 256.54 180)
		(effects
			(font
				(size 1.27 1.27)
			)
			(justify right bottom)
		)
	)
	(label "USBC0_ISET"
		(at 314.96 34.29 180)
		(effects
			(font
				(size 1.27 1.27)
			)
			(justify right bottom)
		)
	)
	(label "~{CS}"
		(at 44.45 232.41 0)
		(effects
			(font
				(size 1.27 1.27)
			)
			(justify left bottom)
		)
	)
	(label "PDC_LDO_1V8"
		(at 173.99 187.96 180)
		(effects
			(font
				(size 1.27 1.27)
			)
			(justify right bottom)
		)
	)
	(label "PDC_LDO_3V3"
		(at 328.93 194.31 0)
		(effects
			(font
				(size 1.27 1.27)
			)
			(justify left bottom)
		)
	)
	(label "PDC_GPIO15"
		(at 229.87 234.95 180)
		(effects
			(font
				(size 1.27 1.27)
			)
			(justify right bottom)
		)
	)
	(label "PDC_MOSI"
		(at 113.03 203.2 180)
		(effects
			(font
				(size 1.27 1.27)
			)
			(justify right bottom)
		)
	)
	(label "MISO"
		(at 78.74 214.63 180)
		(effects
			(font
				(size 1.27 1.27)
			)
			(justify right bottom)
		)
	)
	(label "FTDI_CBUS3{slash}SCL"
		(at 91.44 116.84 0)
		(effects
			(font
				(size 1.27 1.27)
			)
			(justify left bottom)
		)
	)
	(hierarchical_label "I2C_{SYS}{I2C}"
		(shape input)
		(at 86.36 251.46 0)
		(effects
			(font
				(size 1.27 1.27)
			)
			(justify left)
		)
	)
	(hierarchical_label "UART3_DEBUG{UART}"
		(shape bidirectional)
		(at 133.35 93.98 0)
		(effects
			(font
				(size 1.27 1.27)
			)
			(justify left)
		)
	)
	(hierarchical_label "~{PDC_I2C1_IRQ}"
		(shape output)
		(at 285.75 242.57 0)
		(effects
			(font
				(size 1.27 1.27)
			)
			(justify left)
		)
	)
	(hierarchical_label "USBC_HPD"
		(shape output)
		(at 248.92 203.2 0)
		(effects
			(font
				(size 1.27 1.27)
			)
			(justify left)
		)
	)
	(hierarchical_label "~{RESET}"
		(shape input)
		(at 77.47 137.16 180)
		(effects
			(font
				(size 1.27 1.27)
			)
			(justify right)
		)
	)
	(hierarchical_label "I2C_{SYS}{I2C}"
		(shape bidirectional)
		(at 285.75 245.11 0)
		(effects
			(font
				(size 1.27 1.27)
			)
			(justify left)
		)
	)
	(hierarchical_label "USBPD2_HV"
		(shape bidirectional)
		(at 207.01 54.61 180)
		(effects
			(font
				(size 1.27 1.27)
			)
			(justify right)
		)
	)
	(hierarchical_label "USBC1_CTL0"
		(shape output)
		(at 238.76 195.58 0)
		(effects
			(font
				(size 1.27 1.27)
			)
			(justify left)
		)
	)
	(hierarchical_label "USBC1_CTL1"
		(shape output)
		(at 238.76 198.12 0)
		(effects
			(font
				(size 1.27 1.27)
			)
			(justify left)
		)
	)
	(hierarchical_label "SPI_{HUB_DEBUG}{SPI}"
		(shape input)
		(at 92.71 229.87 0)
		(effects
			(font
				(size 1.27 1.27)
			)
			(justify left)
		)
	)
	(hierarchical_label "USBC1_5V_PEN"
		(shape output)
		(at 217.17 240.03 0)
		(effects
			(font
				(size 1.27 1.27)
			)
			(justify left)
		)
	)
	(hierarchical_label "USBC1_FLIP"
		(shape output)
		(at 238.76 193.04 0)
		(effects
			(font
				(size 1.27 1.27)
			)
			(justify left)
		)
	)
	(rule_area
		(polyline
			(pts
				(xy 298.45 83.185) (xy 279.4 83.185) (xy 279.4 76.835) (xy 298.45 76.835)
			)
			(stroke
				(width 0)
				(type dash)
			)
			(fill
				(type none)
			)
		)
	)
	(rule_area
		(polyline
			(pts
				(xy 248.92 112.395) (xy 229.87 112.395) (xy 229.87 106.045) (xy 248.92 106.045)
			)
			(stroke
				(width 0)
				(type dash)
			)
			(fill
				(type none)
			)
		)
	)
	(netclass_flag ""
		(length 2.54)
		(shape round)
		(at 229.87 106.045 0)
		(effects
			(font
				(size 1.27 1.27)
			)
			(justify left bottom)
		)
		(property "Netclass" "90Ohm-diff_USB_2.0"
			(at 222.885 101.6 0)
			(effects
				(font
					(size 1.27 1.27)
				)
				(justify left)
			)
		)
		(property "Component Class" ""
			(at 67.31 64.135 0)
			(effects
				(font
					(size 1.27 1.27)
					(italic yes)
				)
				(justify right)
			)
		)
	)
	(netclass_flag ""
		(length 2.54)
		(shape round)
		(at 279.4 83.185 90)
		(effects
			(font
				(size 1.27 1.27)
			)
			(justify left bottom)
		)
		(property "Netclass" "90Ohm-diff_USB_2.0"
			(at 275.336 83.185 0)
			(effects
				(font
					(size 1.27 1.27)
				)
				(justify right)
			)
		)
		(property "Component Class" ""
			(at 237.49 245.745 90)
			(effects
				(font
					(size 1.27 1.27)
					(italic yes)
				)
				(justify right)
			)
		)
	)
	(symbol
		(lib_id "antmicropower:GND")
		(at 153.67 219.71 0)
		(mirror y)
		(unit 1)
		(exclude_from_sim no)
		(in_bom yes)
		(on_board yes)
		(dnp no)
		(property "Reference" "#PWR0219"
			(at 153.67 226.06 0)
			(effects
				(font
					(size 1.27 1.27)
				)
				(justify left bottom)
				(hide yes)
			)
		)
		(property "Value" "GND"
			(at 153.67 223.52 0)
			(effects
				(font
					(size 1.27 1.27)
					(thickness 0.15)
				)
			)
		)
		(property "Footprint" ""
			(at 144.78 227.33 0)
			(effects
				(font
					(size 1.27 1.27)
					(thickness 0.15)
				)
				(justify left bottom)
				(hide yes)
			)
		)
		(property "Datasheet" ""
			(at 144.78 232.41 0)
			(effects
				(font
					(size 1.27 1.27)
					(thickness 0.15)
				)
				(justify left bottom)
				(hide yes)
			)
		)
		(property "Description" ""
			(at 153.67 219.71 0)
			(effects
				(font
					(size 1.27 1.27)
				)
				(hide yes)
			)
		)
		(property "Author" "Antmicro"
			(at 144.78 227.33 0)
			(effects
				(font
					(size 1.27 1.27)
					(thickness 0.15)
				)
				(justify left bottom)
				(hide yes)
			)
		)
		(property "License" "Apache-2.0"
			(at 144.78 229.87 0)
			(effects
				(font
					(size 1.27 1.27)
					(thickness 0.15)
				)
				(justify left bottom)
				(hide yes)
			)
		)
		(pin "1"
		)
		(instances
			(project "usb_debug_pd"
				(path ""
					(reference "#PWR?")
					(unit 1)
				)
			)
			(project "jetson-agx-thor-baseboard"
				(path ""
					(reference "#PWR0219")
					(unit 1)
				)
			)
		)
	)
	(symbol
		(lib_id "antmicropower:GND")
		(at 153.67 198.12 0)
		(mirror y)
		(unit 1)
		(exclude_from_sim no)
		(in_bom yes)
		(on_board yes)
		(dnp no)
		(property "Reference" "#PWR0221"
			(at 153.67 204.47 0)
			(effects
				(font
					(size 1.27 1.27)
				)
				(justify left bottom)
				(hide yes)
			)
		)
		(property "Value" "GND"
			(at 153.67 201.93 0)
			(effects
				(font
					(size 1.27 1.27)
					(thickness 0.15)
				)
			)
		)
		(property "Footprint" ""
			(at 144.78 205.74 0)
			(effects
				(font
					(size 1.27 1.27)
					(thickness 0.15)
				)
				(justify left bottom)
				(hide yes)
			)
		)
		(property "Datasheet" ""
			(at 144.78 210.82 0)
			(effects
				(font
					(size 1.27 1.27)
					(thickness 0.15)
				)
				(justify left bottom)
				(hide yes)
			)
		)
		(property "Description" ""
			(at 153.67 198.12 0)
			(effects
				(font
					(size 1.27 1.27)
				)
				(hide yes)
			)
		)
		(property "Author" "Antmicro"
			(at 144.78 205.74 0)
			(effects
				(font
					(size 1.27 1.27)
					(thickness 0.15)
				)
				(justify left bottom)
				(hide yes)
			)
		)
		(property "License" "Apache-2.0"
			(at 144.78 208.28 0)
			(effects
				(font
					(size 1.27 1.27)
					(thickness 0.15)
				)
				(justify left bottom)
				(hide yes)
			)
		)
		(pin "1"
		)
		(instances
			(project "usb_debug_pd"
				(path ""
					(reference "#PWR?")
					(unit 1)
				)
			)
			(project "jetson-agx-thor-baseboard"
				(path ""
					(reference "#PWR0221")
					(unit 1)
				)
			)
		)
	)
	(symbol
		(lib_id "antmicroResistors0402:R_0R_0402")
		(at 261.62 245.11 180)
		(unit 1)
		(exclude_from_sim no)
		(in_bom yes)
		(on_board yes)
		(dnp no)
		(property "Reference" "R110"
			(at 261.62 244.475 0)
			(effects
				(font
					(size 1.27 1.27)
				)
				(justify right top)
			)
		)
		(property "Value" "R_0R_0402"
			(at 241.3 232.41 0)
			(effects
				(font
					(size 1.27 1.27)
					(thickness 0.15)
				)
				(justify left bottom)
				(hide yes)
			)
		)
		(property "Footprint" "antmicro-footprints:R_0402_1005Metric"
			(at 241.3 229.87 0)
			(effects
				(font
					(size 1.27 1.27)
					(thickness 0.15)
				)
				(justify left bottom)
				(hide yes)
			)
		)
		(property "Datasheet" "https://industrial.panasonic.com/cdbs/www-data/pdf/RDA0000/AOA0000C301.pdf"
			(at 241.3 227.33 0)
			(effects
				(font
					(size 1.27 1.27)
					(thickness 0.15)
				)
				(justify left bottom)
				(hide yes)
			)
		)
		(property "Description" "SMD Chip Resistor, Jumper, 0 ohm, 100 mW, 0402 [1005 Metric], Thick Film, General Purpose"
			(at 261.62 245.11 0)
			(effects
				(font
					(size 1.27 1.27)
				)
				(hide yes)
			)
		)
		(property "Manufacturer" "Panasonic"
			(at 241.3 222.25 0)
			(effects
				(font
					(size 1.27 1.27)
					(thickness 0.15)
				)
				(justify left bottom)
				(hide yes)
			)
		)
		(property "MPN" "ERJ2GE0R00X"
			(at 241.3 224.79 0)
			(effects
				(font
					(size 1.27 1.27)
					(thickness 0.15)
				)
				(justify left bottom)
				(hide yes)
			)
		)
		(property "Val" "0R"
			(at 254 244.475 0)
			(effects
				(font
					(size 1.27 1.27)
					(thickness 0.15)
				)
				(justify right top)
			)
		)
		(property "License" "Apache-2.0"
			(at 241.3 219.71 0)
			(effects
				(font
					(size 1.27 1.27)
					(thickness 0.15)
				)
				(justify left bottom)
				(hide yes)
			)
		)
		(property "Author" "Antmicro"
			(at 241.3 217.17 0)
			(effects
				(font
					(size 1.27 1.27)
					(thickness 0.15)
				)
				(justify left bottom)
				(hide yes)
			)
		)
		(property "Tolerance" "~"
			(at 241.3 234.95 0)
			(effects
				(font
					(size 1.27 1.27)
				)
				(justify left bottom)
				(hide yes)
			)
		)
		(property "Current" "1A"
			(at 241.3 214.63 0)
			(effects
				(font
					(size 1.27 1.27)
					(thickness 0.15)
				)
				(justify left bottom)
				(hide yes)
			)
		)
		(pin "1"
		)
		(pin "2"
		)
		(instances
			(project "usb_debug_pd"
				(path ""
					(reference "R?")
					(unit 1)
				)
			)
			(project "jetson-agx-thor-baseboard"
				(path ""
					(reference "R110")
					(unit 1)
				)
			)
		)
	)
	(symbol
		(lib_id "antmicropower:GND")
		(at 146.05 198.12 0)
		(mirror y)
		(unit 1)
		(exclude_from_sim no)
		(in_bom yes)
		(on_board yes)
		(dnp no)
		(property "Reference" "#PWR0216"
			(at 146.05 204.47 0)
			(effects
				(font
					(size 1.27 1.27)
				)
				(justify left bottom)
				(hide yes)
			)
		)
		(property "Value" "GND"
			(at 146.05 201.93 0)
			(effects
				(font
					(size 1.27 1.27)
					(thickness 0.15)
				)
			)
		)
		(property "Footprint" ""
			(at 137.16 205.74 0)
			(effects
				(font
					(size 1.27 1.27)
					(thickness 0.15)
				)
				(justify left bottom)
				(hide yes)
			)
		)
		(property "Datasheet" ""
			(at 137.16 210.82 0)
			(effects
				(font
					(size 1.27 1.27)
					(thickness 0.15)
				)
				(justify left bottom)
				(hide yes)
			)
		)
		(property "Description" ""
			(at 146.05 198.12 0)
			(effects
				(font
					(size 1.27 1.27)
				)
				(hide yes)
			)
		)
		(property "Author" "Antmicro"
			(at 137.16 205.74 0)
			(effects
				(font
					(size 1.27 1.27)
					(thickness 0.15)
				)
				(justify left bottom)
				(hide yes)
			)
		)
		(property "License" "Apache-2.0"
			(at 137.16 208.28 0)
			(effects
				(font
					(size 1.27 1.27)
					(thickness 0.15)
				)
				(justify left bottom)
				(hide yes)
			)
		)
		(pin "1"
		)
		(instances
			(project "usb_debug_pd"
				(path ""
					(reference "#PWR?")
					(unit 1)
				)
			)
			(project "jetson-agx-thor-baseboard"
				(path ""
					(reference "#PWR0216")
					(unit 1)
				)
			)
		)
	)
	(symbol
		(lib_id "antmicroResistors0402:R_0R_0402")
		(at 92.71 203.2 0)
		(unit 1)
		(exclude_from_sim no)
		(in_bom yes)
		(on_board yes)
		(dnp no)
		(property "Reference" "R382"
			(at 99.822 201.93 0)
			(effects
				(font
					(size 1.27 1.27)
					(thickness 0.15)
				)
			)
		)
		(property "Value" "R_0R_0402"
			(at 113.03 215.9 0)
			(effects
				(font
					(size 1.27 1.27)
					(thickness 0.15)
				)
				(justify left bottom)
				(hide yes)
			)
		)
		(property "Footprint" "antmicro-footprints:R_0402_1005Metric"
			(at 113.03 218.44 0)
			(effects
				(font
					(size 1.27 1.27)
					(thickness 0.15)
				)
				(justify left bottom)
				(hide yes)
			)
		)
		(property "Datasheet" "https://industrial.panasonic.com/cdbs/www-data/pdf/RDA0000/AOA0000C301.pdf"
			(at 113.03 220.98 0)
			(effects
				(font
					(size 1.27 1.27)
					(thickness 0.15)
				)
				(justify left bottom)
				(hide yes)
			)
		)
		(property "Description" "SMD Chip Resistor, Jumper, 0 ohm, 100 mW, 0402 [1005 Metric], Thick Film, General Purpose"
			(at 113.03 236.22 0)
			(effects
				(font
					(size 1.27 1.27)
				)
				(justify left bottom)
				(hide yes)
			)
		)
		(property "MPN" "ERJ2GE0R00X"
			(at 113.03 223.52 0)
			(effects
				(font
					(size 1.27 1.27)
					(thickness 0.15)
				)
				(justify left bottom)
				(hide yes)
			)
		)
		(property "Manufacturer" "Panasonic"
			(at 113.03 226.06 0)
			(effects
				(font
					(size 1.27 1.27)
					(thickness 0.15)
				)
				(justify left bottom)
				(hide yes)
			)
		)
		(property "License" "Apache-2.0"
			(at 113.03 228.6 0)
			(effects
				(font
					(size 1.27 1.27)
					(thickness 0.15)
				)
				(justify left bottom)
				(hide yes)
			)
		)
		(property "Author" "Antmicro"
			(at 113.03 231.14 0)
			(effects
				(font
					(size 1.27 1.27)
					(thickness 0.15)
				)
				(justify left bottom)
				(hide yes)
			)
		)
		(property "Val" "0R"
			(at 91.948 201.93 0)
			(effects
				(font
					(size 1.27 1.27)
					(thickness 0.15)
				)
			)
		)
		(property "Tolerance" "~"
			(at 113.03 213.36 0)
			(effects
				(font
					(size 1.27 1.27)
				)
				(justify left bottom)
				(hide yes)
			)
		)
		(property "Current" "1A"
			(at 113.03 233.68 0)
			(effects
				(font
					(size 1.27 1.27)
					(thickness 0.15)
				)
				(justify left bottom)
				(hide yes)
			)
		)
		(pin "2"
		)
		(pin "1"
		)
		(instances
			(project "jetson-agx-thor-baseboard"
				(path ""
					(reference "R382")
					(unit 1)
				)
			)
		)
	)
	(symbol
		(lib_id "antmicroTVSDiodes:ESDA25P35-1U1M")
		(at 347.98 33.02 270)
		(unit 1)
		(exclude_from_sim no)
		(in_bom yes)
		(on_board yes)
		(dnp no)
		(property "Reference" "D23"
			(at 349.885 34.29 90)
			(effects
				(font
					(size 1.27 1.27)
				)
				(justify left)
			)
		)
		(property "Value" "ESDA25P35-1U1M"
			(at 332.74 54.61 0)
			(effects
				(font
					(size 1.27 1.27)
					(thickness 0.15)
				)
				(justify left bottom)
				(hide yes)
			)
		)
		(property "Footprint" "antmicro-footprints:QFN-2L_1.6x1x0.55mm"
			(at 337.82 57.15 0)
			(effects
				(font
					(size 1.27 1.27)
					(thickness 0.15)
				)
				(justify left bottom)
				(hide yes)
			)
		)
		(property "Datasheet" "https://www.st.com/resource/en/datasheet/esda25p35-1u1m.pdf"
			(at 335.28 57.15 0)
			(effects
				(font
					(size 1.27 1.27)
					(thickness 0.15)
				)
				(justify left bottom)
				(hide yes)
			)
		)
		(property "Description" "Unidirectional TVS, 30 kV, QFN-2L, 22 V, 195 pF"
			(at 322.58 57.15 0)
			(effects
				(font
					(size 1.27 1.27)
				)
				(justify left bottom)
				(hide yes)
			)
		)
		(property "Manufacturer" "STMicroelectronics"
			(at 330.2 57.15 0)
			(effects
				(font
					(size 1.27 1.27)
					(thickness 0.15)
				)
				(justify left bottom)
				(hide yes)
			)
		)
		(property "MPN" "ESDA25P35-1U1M"
			(at 350.266 35.56 0)
			(effects
				(font
					(size 1.27 1.27)
					(thickness 0.15)
				)
				(justify left bottom)
			)
		)
		(property "Author" "Antmicro"
			(at 327.66 57.15 0)
			(effects
				(font
					(size 1.27 1.27)
					(thickness 0.15)
				)
				(justify left bottom)
				(hide yes)
			)
		)
		(property "License" "Apache-2.0"
			(at 325.12 57.15 0)
			(effects
				(font
					(size 1.27 1.27)
					(thickness 0.15)
				)
				(justify left bottom)
				(hide yes)
			)
		)
		(pin "1"
		)
		(pin "2"
		)
		(instances
			(project "usb_debug_pd"
				(path ""
					(reference "D?")
					(unit 1)
				)
			)
			(project "jetson-agx-thor-baseboard"
				(path ""
					(reference "D23")
					(unit 1)
				)
			)
		)
	)
	(symbol
		(lib_id "antmicropower:+3V3")
		(at 364.49 194.31 0)
		(unit 1)
		(exclude_from_sim no)
		(in_bom yes)
		(on_board yes)
		(dnp no)
		(fields_autoplaced yes)
		(property "Reference" "#PWR0228"
			(at 379.73 194.31 0)
			(effects
				(font
					(size 1.27 1.27)
					(thickness 0.15)
				)
				(justify left bottom)
				(hide yes)
			)
		)
		(property "Value" "FLASH_PWR"
			(at 364.49 189.23 0)
			(effects
				(font
					(size 1.27 1.27)
					(thickness 0.15)
				)
			)
		)
		(property "Footprint" ""
			(at 379.73 201.93 0)
			(effects
				(font
					(size 1.27 1.27)
					(thickness 0.15)
				)
				(justify left bottom)
				(hide yes)
			)
		)
		(property "Datasheet" ""
			(at 379.73 204.47 0)
			(effects
				(font
					(size 1.27 1.27)
					(thickness 0.15)
				)
				(justify left bottom)
				(hide yes)
			)
		)
		(property "Description" ""
			(at 364.49 194.31 0)
			(effects
				(font
					(size 1.27 1.27)
				)
				(hide yes)
			)
		)
		(property "Author" "Antmicro"
			(at 379.73 196.85 0)
			(effects
				(font
					(size 1.27 1.27)
					(thickness 0.15)
				)
				(justify left bottom)
				(hide yes)
			)
		)
		(property "License" "Apache-2.0"
			(at 379.73 199.39 0)
			(effects
				(font
					(size 1.27 1.27)
					(thickness 0.15)
				)
				(justify left bottom)
				(hide yes)
			)
		)
		(pin "1"
		)
		(instances
			(project "usb_debug_pd"
				(path ""
					(reference "#PWR?")
					(unit 1)
				)
			)
			(project "jetson-agx-thor-baseboard"
				(path ""
					(reference "#PWR0228")
					(unit 1)
				)
			)
		)
	)
	(symbol
		(lib_id "antmicroDiodesRectifiersSingle:RB521S30T1G")
		(at 40.64 254 0)
		(unit 1)
		(exclude_from_sim no)
		(in_bom yes)
		(on_board yes)
		(dnp no)
		(property "Reference" "D16"
			(at 43.18 247.65 0)
			(effects
				(font
					(size 1.27 1.27)
					(thickness 0.15)
				)
			)
		)
		(property "Value" "RB521S30T1G"
			(at 63.5 269.24 0)
			(effects
				(font
					(size 1.27 1.27)
					(thickness 0.15)
				)
				(justify left bottom)
				(hide yes)
			)
		)
		(property "Footprint" "antmicro-footprints:SOD-523"
			(at 63.5 264.16 0)
			(effects
				(font
					(size 1.27 1.27)
					(thickness 0.15)
				)
				(justify left bottom)
				(hide yes)
			)
		)
		(property "Datasheet" "https://www.onsemi.com/pdf/datasheet/rb521s30t1-d.pdf"
			(at 63.5 266.7 0)
			(effects
				(font
					(size 1.27 1.27)
					(thickness 0.15)
				)
				(justify left bottom)
				(hide yes)
			)
		)
		(property "Description" "Small Signal Schottky Diode, Single, 30 V, 200 mA, 500 mV, 1 A, 125 °C"
			(at 40.64 254 0)
			(effects
				(font
					(size 1.27 1.27)
				)
				(hide yes)
			)
		)
		(property "MPN" "RB521S30T1G"
			(at 43.18 250.19 0)
			(effects
				(font
					(size 1.27 1.27)
					(thickness 0.15)
				)
			)
		)
		(property "Manufacturer" "ON Semiconductor"
			(at 63.5 271.78 0)
			(effects
				(font
					(size 1.27 1.27)
					(thickness 0.15)
				)
				(justify left bottom)
				(hide yes)
			)
		)
		(property "Author" "Antmicro"
			(at 63.5 274.32 0)
			(effects
				(font
					(size 1.27 1.27)
					(thickness 0.15)
				)
				(justify left bottom)
				(hide yes)
			)
		)
		(property "License" "Apache-2.0"
			(at 63.5 276.86 0)
			(effects
				(font
					(size 1.27 1.27)
					(thickness 0.15)
				)
				(justify left bottom)
				(hide yes)
			)
		)
		(pin "1"
		)
		(pin "2"
		)
		(instances
			(project "usb_debug_pd"
				(path ""
					(reference "D?")
					(unit 1)
				)
			)
			(project "jetson-agx-thor-baseboard"
				(path ""
					(reference "D16")
					(unit 1)
				)
			)
		)
	)
	(symbol
		(lib_id "antmicroResistors0402:R_200R_0402")
		(at 120.65 95.25 90)
		(unit 1)
		(exclude_from_sim no)
		(in_bom yes)
		(on_board yes)
		(dnp no)
		(fields_autoplaced yes)
		(property "Reference" "R120"
			(at 123.19 91.4399 90)
			(effects
				(font
					(size 1.27 1.27)
				)
				(justify right)
			)
		)
		(property "Value" "R_200R_0402"
			(at 133.35 74.93 0)
			(effects
				(font
					(size 1.27 1.27)
					(thickness 0.15)
				)
				(justify left bottom)
				(hide yes)
			)
		)
		(property "Footprint" "antmicro-footprints:R_0402_1005Metric"
			(at 135.89 74.93 0)
			(effects
				(font
					(size 1.27 1.27)
					(thickness 0.15)
				)
				(justify left bottom)
				(hide yes)
			)
		)
		(property "Datasheet" "https://www.bourns.com/docs/product-datasheets/cr.pdf"
			(at 138.43 74.93 0)
			(effects
				(font
					(size 1.27 1.27)
					(thickness 0.15)
				)
				(justify left bottom)
				(hide yes)
			)
		)
		(property "Description" "SMD Chip Resistor, 200 ohm, ± 1%, 62.5 mW, 0402 [1005 Metric], Thick Film, General Purpose"
			(at 120.65 95.25 0)
			(effects
				(font
					(size 1.27 1.27)
				)
				(hide yes)
			)
		)
		(property "Manufacturer" "Bourns"
			(at 143.51 74.93 0)
			(effects
				(font
					(size 1.27 1.27)
					(thickness 0.15)
				)
				(justify left bottom)
				(hide yes)
			)
		)
		(property "MPN" "CR0402-FX-2000GLF"
			(at 140.97 74.93 0)
			(effects
				(font
					(size 1.27 1.27)
					(thickness 0.15)
				)
				(justify left bottom)
				(hide yes)
			)
		)
		(property "Val" "200R"
			(at 123.19 93.98 90)
			(effects
				(font
					(size 1.27 1.27)
					(thickness 0.15)
				)
				(justify right)
			)
		)
		(property "License" "Apache-2.0"
			(at 146.05 74.93 0)
			(effects
				(font
					(size 1.27 1.27)
					(thickness 0.15)
				)
				(justify left bottom)
				(hide yes)
			)
		)
		(property "Author" "Antmicro"
			(at 148.59 74.93 0)
			(effects
				(font
					(size 1.27 1.27)
					(thickness 0.15)
				)
				(justify left bottom)
				(hide yes)
			)
		)
		(property "Tolerance" "1%"
			(at 130.81 74.93 0)
			(effects
				(font
					(size 1.27 1.27)
				)
				(justify left bottom)
				(hide yes)
			)
		)
		(pin "1"
		)
		(pin "2"
		)
		(instances
			(project "usb_debug_pd"
				(path ""
					(reference "R?")
					(unit 1)
				)
			)
			(project "jetson-agx-thor-baseboard"
				(path ""
					(reference "R120")
					(unit 1)
				)
			)
		)
	)
	(symbol
		(lib_id "antmicropower:GND")
		(at 214.63 63.5 0)
		(mirror y)
		(unit 1)
		(exclude_from_sim no)
		(in_bom yes)
		(on_board yes)
		(dnp no)
		(property "Reference" "#PWR0261"
			(at 214.63 69.85 0)
			(effects
				(font
					(size 1.27 1.27)
				)
				(justify left bottom)
				(hide yes)
			)
		)
		(property "Value" "GND"
			(at 214.63 67.31 0)
			(effects
				(font
					(size 1.27 1.27)
					(thickness 0.15)
				)
			)
		)
		(property "Footprint" ""
			(at 205.74 71.12 0)
			(effects
				(font
					(size 1.27 1.27)
					(thickness 0.15)
				)
				(justify left bottom)
				(hide yes)
			)
		)
		(property "Datasheet" ""
			(at 205.74 76.2 0)
			(effects
				(font
					(size 1.27 1.27)
					(thickness 0.15)
				)
				(justify left bottom)
				(hide yes)
			)
		)
		(property "Description" ""
			(at 214.63 63.5 0)
			(effects
				(font
					(size 1.27 1.27)
				)
				(hide yes)
			)
		)
		(property "Author" "Antmicro"
			(at 205.74 71.12 0)
			(effects
				(font
					(size 1.27 1.27)
					(thickness 0.15)
				)
				(justify left bottom)
				(hide yes)
			)
		)
		(property "License" "Apache-2.0"
			(at 205.74 73.66 0)
			(effects
				(font
					(size 1.27 1.27)
					(thickness 0.15)
				)
				(justify left bottom)
				(hide yes)
			)
		)
		(pin "1"
		)
		(instances
			(project "usb_debug_pd"
				(path ""
					(reference "#PWR?")
					(unit 1)
				)
			)
			(project "jetson-agx-thor-baseboard"
				(path ""
					(reference "#PWR0261")
					(unit 1)
				)
			)
		)
	)
	(symbol
		(lib_id "antmicroCapacitors0402:C_4u7_25V_0402")
		(at 214.63 57.15 270)
		(unit 1)
		(exclude_from_sim no)
		(in_bom yes)
		(on_board yes)
		(dnp no)
		(fields_autoplaced yes)
		(property "Reference" "C146"
			(at 217.17 57.1562 90)
			(effects
				(font
					(size 1.27 1.27)
				)
				(justify left)
			)
		)
		(property "Value" "C_4u7_25V_0402"
			(at 204.47 77.47 0)
			(effects
				(font
					(size 1.27 1.27)
					(thickness 0.15)
				)
				(justify left bottom)
				(hide yes)
			)
		)
		(property "Footprint" "antmicro-footprints:C_0402_1005Metric"
			(at 201.93 77.47 0)
			(effects
				(font
					(size 1.27 1.27)
					(thickness 0.15)
				)
				(justify left bottom)
				(hide yes)
			)
		)
		(property "Datasheet" "https://www.murata.com/products/productdetail?partno=GRM155C61E475ME15%23"
			(at 199.39 77.47 0)
			(effects
				(font
					(size 1.27 1.27)
					(thickness 0.15)
				)
				(justify left bottom)
				(hide yes)
			)
		)
		(property "Description" "SMD Multilayer Ceramic Capacitor"
			(at 214.63 57.15 0)
			(effects
				(font
					(size 1.27 1.27)
				)
				(hide yes)
			)
		)
		(property "Manufacturer" "Murata"
			(at 194.31 77.47 0)
			(effects
				(font
					(size 1.27 1.27)
					(thickness 0.15)
				)
				(justify left bottom)
				(hide yes)
			)
		)
		(property "MPN" "GRM155C61E475ME15J"
			(at 196.85 77.47 0)
			(effects
				(font
					(size 1.27 1.27)
					(thickness 0.15)
				)
				(justify left bottom)
				(hide yes)
			)
		)
		(property "Val" "4u7"
			(at 217.17 59.6963 90)
			(effects
				(font
					(size 1.27 1.27)
					(thickness 0.15)
				)
				(justify left)
			)
		)
		(property "License" "Apache-2.0"
			(at 191.77 77.47 0)
			(effects
				(font
					(size 1.27 1.27)
					(thickness 0.15)
				)
				(justify left bottom)
				(hide yes)
			)
		)
		(property "Author" "Antmicro"
			(at 189.23 77.47 0)
			(effects
				(font
					(size 1.27 1.27)
					(thickness 0.15)
				)
				(justify left bottom)
				(hide yes)
			)
		)
		(property "Voltage" "25V"
			(at 217.17 62.2362 90)
			(effects
				(font
					(size 1.27 1.27)
				)
				(justify left)
			)
		)
		(property "Dielectric" "X5S"
			(at 184.15 77.47 0)
			(effects
				(font
					(size 1.27 1.27)
				)
				(justify left bottom)
				(hide yes)
			)
		)
		(pin "1"
		)
		(pin "2"
		)
		(instances
			(project "usb_debug_pd"
				(path ""
					(reference "C?")
					(unit 1)
				)
			)
			(project "jetson-agx-thor-baseboard"
				(path ""
					(reference "C146")
					(unit 1)
				)
			)
		)
	)
	(symbol
		(lib_id "antmicropower:GND")
		(at 209.55 63.5 0)
		(mirror y)
		(unit 1)
		(exclude_from_sim no)
		(in_bom yes)
		(on_board yes)
		(dnp no)
		(property "Reference" "#PWR0260"
			(at 209.55 69.85 0)
			(effects
				(font
					(size 1.27 1.27)
				)
				(justify left bottom)
				(hide yes)
			)
		)
		(property "Value" "GND"
			(at 209.55 67.31 0)
			(effects
				(font
					(size 1.27 1.27)
					(thickness 0.15)
				)
			)
		)
		(property "Footprint" ""
			(at 200.66 71.12 0)
			(effects
				(font
					(size 1.27 1.27)
					(thickness 0.15)
				)
				(justify left bottom)
				(hide yes)
			)
		)
		(property "Datasheet" ""
			(at 200.66 76.2 0)
			(effects
				(font
					(size 1.27 1.27)
					(thickness 0.15)
				)
				(justify left bottom)
				(hide yes)
			)
		)
		(property "Description" ""
			(at 209.55 63.5 0)
			(effects
				(font
					(size 1.27 1.27)
				)
				(hide yes)
			)
		)
		(property "Author" "Antmicro"
			(at 200.66 71.12 0)
			(effects
				(font
					(size 1.27 1.27)
					(thickness 0.15)
				)
				(justify left bottom)
				(hide yes)
			)
		)
		(property "License" "Apache-2.0"
			(at 200.66 73.66 0)
			(effects
				(font
					(size 1.27 1.27)
					(thickness 0.15)
				)
				(justify left bottom)
				(hide yes)
			)
		)
		(pin "1"
		)
		(instances
			(project "usb_debug_pd"
				(path ""
					(reference "#PWR?")
					(unit 1)
				)
			)
			(project "jetson-agx-thor-baseboard"
				(path ""
					(reference "#PWR0260")
					(unit 1)
				)
			)
		)
	)
	(symbol
		(lib_id "antmicroResistors0402:R_4k7_0402")
		(at 240.03 222.25 270)
		(unit 1)
		(exclude_from_sim no)
		(in_bom no)
		(on_board yes)
		(dnp yes)
		(property "Reference" "R104"
			(at 239.522 222.758 0)
			(effects
				(font
					(size 1.27 1.27)
				)
				(justify right top)
			)
		)
		(property "Value" "R_4k7_0402"
			(at 227.33 242.57 0)
			(effects
				(font
					(size 1.27 1.27)
					(thickness 0.15)
				)
				(justify left bottom)
				(hide yes)
			)
		)
		(property "Footprint" "antmicro-footprints:R_0402_1005Metric"
			(at 224.79 242.57 0)
			(effects
				(font
					(size 1.27 1.27)
					(thickness 0.15)
				)
				(justify left bottom)
				(hide yes)
			)
		)
		(property "Datasheet" "https://www.bourns.com/docs/product-datasheets/cr.pdf"
			(at 222.25 242.57 0)
			(effects
				(font
					(size 1.27 1.27)
					(thickness 0.15)
				)
				(justify left bottom)
				(hide yes)
			)
		)
		(property "Description" "SMD Chip Resistor, 4.7 kohm, ± 1%, 62.5 mW, 0402 [1005 Metric], Thick Film, General Purpose"
			(at 240.03 222.25 0)
			(effects
				(font
					(size 1.27 1.27)
				)
				(hide yes)
			)
		)
		(property "Manufacturer" "Bourns"
			(at 217.17 242.57 0)
			(effects
				(font
					(size 1.27 1.27)
					(thickness 0.15)
				)
				(justify left bottom)
				(hide yes)
			)
		)
		(property "MPN" "CR0402-FX-4701GLF"
			(at 219.71 242.57 0)
			(effects
				(font
					(size 1.27 1.27)
					(thickness 0.15)
				)
				(justify left bottom)
				(hide yes)
			)
		)
		(property "Val" "4k7"
			(at 239.395 231.14 0)
			(effects
				(font
					(size 1.27 1.27)
					(thickness 0.15)
				)
				(justify right top)
			)
		)
		(property "License" "Apache-2.0"
			(at 214.63 242.57 0)
			(effects
				(font
					(size 1.27 1.27)
					(thickness 0.15)
				)
				(justify left bottom)
				(hide yes)
			)
		)
		(property "Author" "Antmicro"
			(at 212.09 242.57 0)
			(effects
				(font
					(size 1.27 1.27)
					(thickness 0.15)
				)
				(justify left bottom)
				(hide yes)
			)
		)
		(property "Tolerance" "1%"
			(at 229.87 242.57 0)
			(effects
				(font
					(size 1.27 1.27)
				)
				(justify left bottom)
				(hide yes)
			)
		)
		(pin "1"
		)
		(pin "2"
		)
		(instances
			(project "usb_debug_pd"
				(path ""
					(reference "R?")
					(unit 1)
				)
			)
			(project "jetson-agx-thor-baseboard"
				(path ""
					(reference "R104")
					(unit 1)
				)
			)
		)
	)
	(symbol
		(lib_id "antmicroInterfaceControllers:TPS65988DHRSHR")
		(at 256.54 66.04 0)
		(mirror y)
		(unit 2)
		(exclude_from_sim no)
		(in_bom yes)
		(on_board yes)
		(dnp no)
		(property "Reference" "U30"
			(at 240.665 58.42 0)
			(effects
				(font
					(size 1.27 1.27)
				)
			)
		)
		(property "Value" "TPS65988DHRSHR"
			(at 207.01 71.12 0)
			(effects
				(font
					(size 1.27 1.27)
					(thickness 0.15)
				)
				(justify left bottom)
				(hide yes)
			)
		)
		(property "Footprint" "antmicro-footprints:IC_TPS65987DDHRSHR"
			(at 207.01 73.66 0)
			(effects
				(font
					(size 1.27 1.27)
					(thickness 0.15)
				)
				(justify left bottom)
				(hide yes)
			)
		)
		(property "Datasheet" "https://www.ti.com/lit/ds/symlink/tps65988.pdf?ts=1662726631004&ref_url=https%253A%252F%252Fwww.ti.com%252Fproduct%252FTPS65988"
			(at 207.01 76.2 0)
			(effects
				(font
					(size 1.27 1.27)
					(thickness 0.15)
				)
				(justify left bottom)
				(hide yes)
			)
		)
		(property "Description" "USB, Type-C Controller PMIC 56-VQFN (7x7)"
			(at 256.54 66.04 0)
			(effects
				(font
					(size 1.27 1.27)
				)
				(hide yes)
			)
		)
		(property "MPN" "TPS65988DHRSHR "
			(at 240.665 60.96 0)
			(effects
				(font
					(size 1.27 1.27)
					(thickness 0.15)
				)
			)
		)
		(property "Manufacturer" "Texas Instruments"
			(at 207.01 81.28 0)
			(effects
				(font
					(size 1.27 1.27)
					(thickness 0.15)
				)
				(justify left bottom)
				(hide yes)
			)
		)
		(property "License" "Apache-2.0"
			(at 207.01 83.82 0)
			(effects
				(font
					(size 1.27 1.27)
					(thickness 0.15)
				)
				(justify left bottom)
				(hide yes)
			)
		)
		(property "Author" "Antmicro"
			(at 207.01 86.36 0)
			(effects
				(font
					(size 1.27 1.27)
					(thickness 0.15)
				)
				(justify left bottom)
				(hide yes)
			)
		)
		(pin "10"
		)
		(pin "16"
		)
		(pin "17"
		)
		(pin "18"
		)
		(pin "20"
		)
		(pin "21"
		)
		(pin "22"
		)
		(pin "23"
		)
		(pin "27"
		)
		(pin "28"
		)
		(pin "29"
		)
		(pin "30"
		)
		(pin "31"
		)
		(pin "32"
		)
		(pin "33"
		)
		(pin "34"
		)
		(pin "35"
		)
		(pin "36"
		)
		(pin "37"
		)
		(pin "38"
		)
		(pin "39"
		)
		(pin "40"
		)
		(pin "41"
		)
		(pin "42"
		)
		(pin "43"
		)
		(pin "44"
		)
		(pin "48"
		)
		(pin "49"
		)
		(pin "5"
		)
		(pin "51"
		)
		(pin "59"
		)
		(pin "6"
		)
		(pin "9"
		)
		(pin "11"
		)
		(pin "13"
		)
		(pin "15"
		)
		(pin "19"
		)
		(pin "24"
		)
		(pin "25"
		)
		(pin "26"
		)
		(pin "50"
		)
		(pin "53"
		)
		(pin "58"
		)
		(pin "8"
		)
		(pin "1"
		)
		(pin "3"
		)
		(pin "45"
		)
		(pin "46"
		)
		(pin "47"
		)
		(pin "52"
		)
		(pin "54"
		)
		(pin "55"
		)
		(pin "56"
		)
		(pin "57"
		)
		(pin "7"
		)
		(instances
			(project "usb_debug_pd"
				(path ""
					(reference "U?")
					(unit 1)
				)
			)
			(project "jetson-agx-thor-baseboard"
				(path ""
					(reference "U30")
					(unit 2)
				)
			)
		)
	)
	(symbol
		(lib_id "antmicroTestPoints:TP_0.75mm_SMD")
		(at 233.68 209.55 0)
		(unit 1)
		(exclude_from_sim no)
		(in_bom no)
		(on_board yes)
		(dnp no)
		(property "Reference" "TP11"
			(at 237.49 210.185 0)
			(effects
				(font
					(size 1.27 1.27)
				)
				(justify left bottom)
			)
		)
		(property "Value" "TP_0.75mm_SMD"
			(at 243.84 213.36 0)
			(effects
				(font
					(size 1.27 1.27)
					(thickness 0.15)
				)
				(justify left bottom)
				(hide yes)
			)
		)
		(property "Footprint" "antmicro-footprints:TP_SMD_0.75mm"
			(at 243.84 215.9 0)
			(effects
				(font
					(size 1.27 1.27)
					(thickness 0.15)
				)
				(justify left bottom)
				(hide yes)
			)
		)
		(property "Datasheet" ""
			(at 251.46 222.25 0)
			(effects
				(font
					(size 1.27 1.27)
					(thickness 0.15)
				)
				(justify left bottom)
				(hide yes)
			)
		)
		(property "Description" "SMT test point"
			(at 233.68 209.55 0)
			(effects
				(font
					(size 1.27 1.27)
				)
				(hide yes)
			)
		)
		(property "MPN" ""
			(at 244.475 220.98 0)
			(effects
				(font
					(size 1.27 1.27)
					(thickness 0.15)
				)
				(justify left bottom)
				(hide yes)
			)
		)
		(property "Manufacturer" ""
			(at 244.475 215.9 0)
			(effects
				(font
					(size 1.27 1.27)
					(thickness 0.15)
				)
				(justify left bottom)
				(hide yes)
			)
		)
		(property "Author" "Antmicro"
			(at 243.84 218.44 0)
			(effects
				(font
					(size 1.27 1.27)
					(thickness 0.15)
				)
				(justify left bottom)
				(hide yes)
			)
		)
		(property "License" "Apache-2.0"
			(at 243.84 220.98 0)
			(effects
				(font
					(size 1.27 1.27)
					(thickness 0.15)
				)
				(justify left bottom)
				(hide yes)
			)
		)
		(pin "1"
		)
		(instances
			(project "usb_debug_pd"
				(path ""
					(reference "TP?")
					(unit 1)
				)
			)
			(project "jetson-agx-thor-baseboard"
				(path ""
					(reference "TP11")
					(unit 1)
				)
			)
		)
	)
	(symbol
		(lib_id "antmicropower:GND")
		(at 153.67 231.14 0)
		(mirror y)
		(unit 1)
		(exclude_from_sim no)
		(in_bom yes)
		(on_board yes)
		(dnp no)
		(property "Reference" "#PWR0220"
			(at 153.67 237.49 0)
			(effects
				(font
					(size 1.27 1.27)
				)
				(justify left bottom)
				(hide yes)
			)
		)
		(property "Value" "GND"
			(at 153.67 234.95 0)
			(effects
				(font
					(size 1.27 1.27)
					(thickness 0.15)
				)
			)
		)
		(property "Footprint" ""
			(at 144.78 238.76 0)
			(effects
				(font
					(size 1.27 1.27)
					(thickness 0.15)
				)
				(justify left bottom)
				(hide yes)
			)
		)
		(property "Datasheet" ""
			(at 144.78 243.84 0)
			(effects
				(font
					(size 1.27 1.27)
					(thickness 0.15)
				)
				(justify left bottom)
				(hide yes)
			)
		)
		(property "Description" ""
			(at 153.67 231.14 0)
			(effects
				(font
					(size 1.27 1.27)
				)
				(hide yes)
			)
		)
		(property "Author" "Antmicro"
			(at 144.78 238.76 0)
			(effects
				(font
					(size 1.27 1.27)
					(thickness 0.15)
				)
				(justify left bottom)
				(hide yes)
			)
		)
		(property "License" "Apache-2.0"
			(at 144.78 241.3 0)
			(effects
				(font
					(size 1.27 1.27)
					(thickness 0.15)
				)
				(justify left bottom)
				(hide yes)
			)
		)
		(pin "1"
		)
		(instances
			(project "usb_debug_pd"
				(path ""
					(reference "#PWR?")
					(unit 1)
				)
			)
			(project "jetson-agx-thor-baseboard"
				(path ""
					(reference "#PWR0220")
					(unit 1)
				)
			)
		)
	)
	(symbol
		(lib_id "antmicroCapacitors0402:C_100n_0402")
		(at 45.72 100.33 90)
		(mirror x)
		(unit 1)
		(exclude_from_sim no)
		(in_bom yes)
		(on_board yes)
		(dnp no)
		(fields_autoplaced yes)
		(property "Reference" "C233"
			(at 43.18 101.6063 90)
			(effects
				(font
					(size 1.27 1.27)
				)
				(justify left)
			)
		)
		(property "Value" "C_100n_0402"
			(at 55.88 120.65 0)
			(effects
				(font
					(size 1.27 1.27)
					(thickness 0.15)
				)
				(justify left bottom)
				(hide yes)
			)
		)
		(property "Footprint" "antmicro-footprints:C_0402_1005Metric"
			(at 58.42 120.65 0)
			(effects
				(font
					(size 1.27 1.27)
					(thickness 0.15)
				)
				(justify left bottom)
				(hide yes)
			)
		)
		(property "Datasheet" "https://www.murata.com/products/productdetail?partno=GRM155R61H104KE14%23"
			(at 60.96 120.65 0)
			(effects
				(font
					(size 1.27 1.27)
					(thickness 0.15)
				)
				(justify left bottom)
				(hide yes)
			)
		)
		(property "Description" "SMD Multilayer Ceramic Capacitor, 0.1 µF, 50 V, 0402 [1005 Metric], ± 10%, X5R, GRM Series"
			(at 45.72 100.33 0)
			(effects
				(font
					(size 1.27 1.27)
				)
				(hide yes)
			)
		)
		(property "MPN" "GRM155R61H104KE14D"
			(at 63.5 120.65 0)
			(effects
				(font
					(size 1.27 1.27)
					(thickness 0.15)
				)
				(justify left bottom)
				(hide yes)
			)
		)
		(property "Manufacturer" "Murata"
			(at 66.04 120.65 0)
			(effects
				(font
					(size 1.27 1.27)
					(thickness 0.15)
				)
				(justify left bottom)
				(hide yes)
			)
		)
		(property "Val" "100n"
			(at 43.18 104.1463 90)
			(effects
				(font
					(size 1.27 1.27)
					(thickness 0.15)
				)
				(justify left)
			)
		)
		(property "License" "Apache-2.0"
			(at 68.58 120.65 0)
			(effects
				(font
					(size 1.27 1.27)
					(thickness 0.15)
				)
				(justify left bottom)
				(hide yes)
			)
		)
		(property "Author" "Antmicro"
			(at 71.12 120.65 0)
			(effects
				(font
					(size 1.27 1.27)
					(thickness 0.15)
				)
				(justify left bottom)
				(hide yes)
			)
		)
		(property "Voltage" "50V"
			(at 73.66 120.65 0)
			(effects
				(font
					(size 1.27 1.27)
				)
				(justify left bottom)
				(hide yes)
			)
		)
		(property "Dielectric" "X5R"
			(at 76.2 120.65 0)
			(effects
				(font
					(size 1.27 1.27)
				)
				(justify left bottom)
				(hide yes)
			)
		)
		(pin "1"
		)
		(pin "2"
		)
		(instances
			(project "usb_debug_pd"
				(path ""
					(reference "C?")
					(unit 1)
				)
			)
			(project "jetson-agx-thor-baseboard"
				(path ""
					(reference "C233")
					(unit 1)
				)
			)
		)
	)
	(symbol
		(lib_id "antmicroResistors0402:R_27R_0402")
		(at 259.08 110.49 0)
		(unit 1)
		(exclude_from_sim no)
		(in_bom yes)
		(on_board yes)
		(dnp no)
		(property "Reference" "R148"
			(at 264.16 109.855 0)
			(effects
				(font
					(size 1.27 1.27)
				)
				(justify left bottom)
			)
		)
		(property "Value" "R_27R_0402"
			(at 279.4 123.19 0)
			(effects
				(font
					(size 1.27 1.27)
					(thickness 0.15)
				)
				(justify left bottom)
				(hide yes)
			)
		)
		(property "Footprint" "antmicro-footprints:R_0402_1005Metric"
			(at 279.4 125.73 0)
			(effects
				(font
					(size 1.27 1.27)
					(thickness 0.15)
				)
				(justify left bottom)
				(hide yes)
			)
		)
		(property "Datasheet" "https://www.bourns.com/docs/product-datasheets/cr.pdf"
			(at 279.4 128.27 0)
			(effects
				(font
					(size 1.27 1.27)
					(thickness 0.15)
				)
				(justify left bottom)
				(hide yes)
			)
		)
		(property "Description" "SMD Chip Resistor, 27 ohm, ± 1%, 63 mW, 0402 [1005 Metric], Thick Film, General Purpose"
			(at 259.08 110.49 0)
			(effects
				(font
					(size 1.27 1.27)
				)
				(hide yes)
			)
		)
		(property "Manufacturer" "Bourns"
			(at 279.4 133.35 0)
			(effects
				(font
					(size 1.27 1.27)
					(thickness 0.15)
				)
				(justify left bottom)
				(hide yes)
			)
		)
		(property "MPN" "CR0402-FX-27R0GLF"
			(at 279.4 130.81 0)
			(effects
				(font
					(size 1.27 1.27)
					(thickness 0.15)
				)
				(justify left bottom)
				(hide yes)
			)
		)
		(property "Val" "27R"
			(at 255.27 109.855 0)
			(effects
				(font
					(size 1.27 1.27)
					(thickness 0.15)
				)
				(justify left bottom)
			)
		)
		(property "License" "Apache-2.0"
			(at 279.4 135.89 0)
			(effects
				(font
					(size 1.27 1.27)
					(thickness 0.15)
				)
				(justify left bottom)
				(hide yes)
			)
		)
		(property "Author" "Antmicro"
			(at 279.4 138.43 0)
			(effects
				(font
					(size 1.27 1.27)
					(thickness 0.15)
				)
				(justify left bottom)
				(hide yes)
			)
		)
		(property "Tolerance" "1%"
			(at 279.4 120.65 0)
			(effects
				(font
					(size 1.27 1.27)
				)
				(justify left bottom)
				(hide yes)
			)
		)
		(pin "1"
		)
		(pin "2"
		)
		(instances
			(project "usb_debug_pd"
				(path ""
					(reference "R?")
					(unit 1)
				)
			)
			(project "jetson-agx-thor-baseboard"
				(path ""
					(reference "R148")
					(unit 1)
				)
			)
		)
	)
	(symbol
		(lib_id "antmicropower:GND")
		(at 250.19 33.02 0)
		(mirror y)
		(unit 1)
		(exclude_from_sim no)
		(in_bom yes)
		(on_board yes)
		(dnp no)
		(property "Reference" "#PWR0265"
			(at 250.19 39.37 0)
			(effects
				(font
					(size 1.27 1.27)
				)
				(justify left bottom)
				(hide yes)
			)
		)
		(property "Value" "GND"
			(at 250.19 36.83 0)
			(effects
				(font
					(size 1.27 1.27)
					(thickness 0.15)
				)
			)
		)
		(property "Footprint" ""
			(at 241.3 40.64 0)
			(effects
				(font
					(size 1.27 1.27)
					(thickness 0.15)
				)
				(justify left bottom)
				(hide yes)
			)
		)
		(property "Datasheet" ""
			(at 241.3 45.72 0)
			(effects
				(font
					(size 1.27 1.27)
					(thickness 0.15)
				)
				(justify left bottom)
				(hide yes)
			)
		)
		(property "Description" ""
			(at 250.19 33.02 0)
			(effects
				(font
					(size 1.27 1.27)
				)
				(hide yes)
			)
		)
		(property "Author" "Antmicro"
			(at 241.3 40.64 0)
			(effects
				(font
					(size 1.27 1.27)
					(thickness 0.15)
				)
				(justify left bottom)
				(hide yes)
			)
		)
		(property "License" "Apache-2.0"
			(at 241.3 43.18 0)
			(effects
				(font
					(size 1.27 1.27)
					(thickness 0.15)
				)
				(justify left bottom)
				(hide yes)
			)
		)
		(pin "1"
		)
		(instances
			(project "usb_debug_pd"
				(path ""
					(reference "#PWR?")
					(unit 1)
				)
			)
			(project "jetson-agx-thor-baseboard"
				(path ""
					(reference "#PWR0265")
					(unit 1)
				)
			)
		)
	)
	(symbol
		(lib_id "antmicroResistors0402:R_100k_0402")
		(at 158.75 229.87 0)
		(unit 1)
		(exclude_from_sim no)
		(in_bom yes)
		(on_board yes)
		(dnp no)
		(property "Reference" "R97"
			(at 163.83 229.235 0)
			(effects
				(font
					(size 1.27 1.27)
				)
				(justify left bottom)
			)
		)
		(property "Value" "R_100k_0402"
			(at 179.07 242.57 0)
			(effects
				(font
					(size 1.27 1.27)
					(thickness 0.15)
				)
				(justify left bottom)
				(hide yes)
			)
		)
		(property "Footprint" "antmicro-footprints:R_0402_1005Metric"
			(at 179.07 245.11 0)
			(effects
				(font
					(size 1.27 1.27)
					(thickness 0.15)
				)
				(justify left bottom)
				(hide yes)
			)
		)
		(property "Datasheet" "https://www.bourns.com/docs/product-datasheets/cr.pdf"
			(at 179.07 247.65 0)
			(effects
				(font
					(size 1.27 1.27)
					(thickness 0.15)
				)
				(justify left bottom)
				(hide yes)
			)
		)
		(property "Description" "SMD Chip Resistor, 100 kohm, ± 1%, 62.5 mW, 0402 [1005 Metric], Thick Film, General Purpose"
			(at 158.75 229.87 0)
			(effects
				(font
					(size 1.27 1.27)
				)
				(hide yes)
			)
		)
		(property "Manufacturer" "Bourns"
			(at 179.07 252.73 0)
			(effects
				(font
					(size 1.27 1.27)
					(thickness 0.15)
				)
				(justify left bottom)
				(hide yes)
			)
		)
		(property "MPN" "CR0402-FX-1003GLF"
			(at 179.07 250.19 0)
			(effects
				(font
					(size 1.27 1.27)
					(thickness 0.15)
				)
				(justify left bottom)
				(hide yes)
			)
		)
		(property "Val" "100k"
			(at 154.305 229.235 0)
			(effects
				(font
					(size 1.27 1.27)
					(thickness 0.15)
				)
				(justify left bottom)
			)
		)
		(property "License" "Apache-2.0"
			(at 179.07 255.27 0)
			(effects
				(font
					(size 1.27 1.27)
					(thickness 0.15)
				)
				(justify left bottom)
				(hide yes)
			)
		)
		(property "Author" "Antmicro"
			(at 179.07 257.81 0)
			(effects
				(font
					(size 1.27 1.27)
					(thickness 0.15)
				)
				(justify left bottom)
				(hide yes)
			)
		)
		(property "Tolerance" "1%"
			(at 179.07 240.03 0)
			(effects
				(font
					(size 1.27 1.27)
				)
				(justify left bottom)
				(hide yes)
			)
		)
		(pin "1"
		)
		(pin "2"
		)
		(instances
			(project "usb_debug_pd"
				(path ""
					(reference "R?")
					(unit 1)
				)
			)
			(project "jetson-agx-thor-baseboard"
				(path ""
					(reference "R97")
					(unit 1)
				)
			)
		)
	)
	(symbol
		(lib_id "antmicropower:GND")
		(at 134.62 72.39 0)
		(unit 1)
		(exclude_from_sim no)
		(in_bom yes)
		(on_board yes)
		(dnp no)
		(property "Reference" "#PWR0244"
			(at 134.62 78.74 0)
			(effects
				(font
					(size 1.27 1.27)
				)
				(justify left bottom)
				(hide yes)
			)
		)
		(property "Value" "GND"
			(at 134.62 76.2 0)
			(effects
				(font
					(size 1.27 1.27)
					(thickness 0.15)
				)
			)
		)
		(property "Footprint" ""
			(at 143.51 80.01 0)
			(effects
				(font
					(size 1.27 1.27)
					(thickness 0.15)
				)
				(justify left bottom)
				(hide yes)
			)
		)
		(property "Datasheet" ""
			(at 143.51 85.09 0)
			(effects
				(font
					(size 1.27 1.27)
					(thickness 0.15)
				)
				(justify left bottom)
				(hide yes)
			)
		)
		(property "Description" ""
			(at 134.62 72.39 0)
			(effects
				(font
					(size 1.27 1.27)
				)
				(hide yes)
			)
		)
		(property "Author" "Antmicro"
			(at 143.51 80.01 0)
			(effects
				(font
					(size 1.27 1.27)
					(thickness 0.15)
				)
				(justify left bottom)
				(hide yes)
			)
		)
		(property "License" "Apache-2.0"
			(at 143.51 82.55 0)
			(effects
				(font
					(size 1.27 1.27)
					(thickness 0.15)
				)
				(justify left bottom)
				(hide yes)
			)
		)
		(pin "1"
		)
		(instances
			(project "usb_debug_pd"
				(path ""
					(reference "#PWR?")
					(unit 1)
				)
			)
			(project "jetson-agx-thor-baseboard"
				(path ""
					(reference "#PWR0244")
					(unit 1)
				)
			)
		)
	)
	(symbol
		(lib_id "antmicroResistors0402:R_0R_0402")
		(at 92.71 208.28 0)
		(unit 1)
		(exclude_from_sim no)
		(in_bom yes)
		(on_board yes)
		(dnp no)
		(property "Reference" "R384"
			(at 99.822 207.01 0)
			(effects
				(font
					(size 1.27 1.27)
					(thickness 0.15)
				)
			)
		)
		(property "Value" "R_0R_0402"
			(at 113.03 220.98 0)
			(effects
				(font
					(size 1.27 1.27)
					(thickness 0.15)
				)
				(justify left bottom)
				(hide yes)
			)
		)
		(property "Footprint" "antmicro-footprints:R_0402_1005Metric"
			(at 113.03 223.52 0)
			(effects
				(font
					(size 1.27 1.27)
					(thickness 0.15)
				)
				(justify left bottom)
				(hide yes)
			)
		)
		(property "Datasheet" "https://industrial.panasonic.com/cdbs/www-data/pdf/RDA0000/AOA0000C301.pdf"
			(at 113.03 226.06 0)
			(effects
				(font
					(size 1.27 1.27)
					(thickness 0.15)
				)
				(justify left bottom)
				(hide yes)
			)
		)
		(property "Description" "SMD Chip Resistor, Jumper, 0 ohm, 100 mW, 0402 [1005 Metric], Thick Film, General Purpose"
			(at 113.03 241.3 0)
			(effects
				(font
					(size 1.27 1.27)
				)
				(justify left bottom)
				(hide yes)
			)
		)
		(property "MPN" "ERJ2GE0R00X"
			(at 113.03 228.6 0)
			(effects
				(font
					(size 1.27 1.27)
					(thickness 0.15)
				)
				(justify left bottom)
				(hide yes)
			)
		)
		(property "Manufacturer" "Panasonic"
			(at 113.03 231.14 0)
			(effects
				(font
					(size 1.27 1.27)
					(thickness 0.15)
				)
				(justify left bottom)
				(hide yes)
			)
		)
		(property "License" "Apache-2.0"
			(at 113.03 233.68 0)
			(effects
				(font
					(size 1.27 1.27)
					(thickness 0.15)
				)
				(justify left bottom)
				(hide yes)
			)
		)
		(property "Author" "Antmicro"
			(at 113.03 236.22 0)
			(effects
				(font
					(size 1.27 1.27)
					(thickness 0.15)
				)
				(justify left bottom)
				(hide yes)
			)
		)
		(property "Val" "0R"
			(at 91.948 207.01 0)
			(effects
				(font
					(size 1.27 1.27)
					(thickness 0.15)
				)
			)
		)
		(property "Tolerance" "~"
			(at 113.03 218.44 0)
			(effects
				(font
					(size 1.27 1.27)
				)
				(justify left bottom)
				(hide yes)
			)
		)
		(property "Current" "1A"
			(at 113.03 238.76 0)
			(effects
				(font
					(size 1.27 1.27)
					(thickness 0.15)
				)
				(justify left bottom)
				(hide yes)
			)
		)
		(pin "2"
		)
		(pin "1"
		)
		(instances
			(project "jetson-agx-thor-baseboard"
				(path ""
					(reference "R384")
					(unit 1)
				)
			)
		)
	)
	(symbol
		(lib_id "antmicroResistors0402:R_0R_0402")
		(at 261.62 31.75 90)
		(unit 1)
		(exclude_from_sim no)
		(in_bom no)
		(on_board yes)
		(dnp yes)
		(property "Reference" "R149"
			(at 262.89 27.94 90)
			(effects
				(font
					(size 1.27 1.27)
				)
				(justify right)
			)
		)
		(property "Value" "R_0R_0402"
			(at 274.32 11.43 0)
			(effects
				(font
					(size 1.27 1.27)
					(thickness 0.15)
				)
				(justify left bottom)
				(hide yes)
			)
		)
		(property "Footprint" "antmicro-footprints:R_0402_1005Metric"
			(at 276.86 11.43 0)
			(effects
				(font
					(size 1.27 1.27)
					(thickness 0.15)
				)
				(justify left bottom)
				(hide yes)
			)
		)
		(property "Datasheet" "https://industrial.panasonic.com/cdbs/www-data/pdf/RDA0000/AOA0000C301.pdf"
			(at 279.4 11.43 0)
			(effects
				(font
					(size 1.27 1.27)
					(thickness 0.15)
				)
				(justify left bottom)
				(hide yes)
			)
		)
		(property "Description" "SMD Chip Resistor, Jumper, 0 ohm, 100 mW, 0402 [1005 Metric], Thick Film, General Purpose"
			(at 261.62 31.75 0)
			(effects
				(font
					(size 1.27 1.27)
				)
				(hide yes)
			)
		)
		(property "Manufacturer" "Panasonic"
			(at 284.48 11.43 0)
			(effects
				(font
					(size 1.27 1.27)
					(thickness 0.15)
				)
				(justify left bottom)
				(hide yes)
			)
		)
		(property "MPN" "ERJ2GE0R00X"
			(at 281.94 11.43 0)
			(effects
				(font
					(size 1.27 1.27)
					(thickness 0.15)
				)
				(justify left bottom)
				(hide yes)
			)
		)
		(property "Val" "0R"
			(at 262.89 30.48 90)
			(effects
				(font
					(size 1.27 1.27)
					(thickness 0.15)
				)
				(justify right)
			)
		)
		(property "License" "Apache-2.0"
			(at 287.02 11.43 0)
			(effects
				(font
					(size 1.27 1.27)
					(thickness 0.15)
				)
				(justify left bottom)
				(hide yes)
			)
		)
		(property "Author" "Antmicro"
			(at 289.56 11.43 0)
			(effects
				(font
					(size 1.27 1.27)
					(thickness 0.15)
				)
				(justify left bottom)
				(hide yes)
			)
		)
		(property "Tolerance" "~"
			(at 271.78 11.43 0)
			(effects
				(font
					(size 1.27 1.27)
				)
				(justify left bottom)
				(hide yes)
			)
		)
		(property "Current" "1A"
			(at 292.1 11.43 0)
			(effects
				(font
					(size 1.27 1.27)
					(thickness 0.15)
				)
				(justify left bottom)
				(hide yes)
			)
		)
		(pin "1"
		)
		(pin "2"
		)
		(instances
			(project "usb_debug_pd"
				(path ""
					(reference "R?")
					(unit 1)
				)
			)
			(project "jetson-agx-thor-baseboard"
				(path ""
					(reference "R149")
					(unit 1)
				)
			)
		)
	)
	(symbol
		(lib_id "antmicroResistors0402:R_470R_0402")
		(at 359.41 38.1 90)
		(unit 1)
		(exclude_from_sim no)
		(in_bom yes)
		(on_board yes)
		(dnp no)
		(fields_autoplaced yes)
		(property "Reference" "R156"
			(at 361.95 34.29 90)
			(effects
				(font
					(size 1.27 1.27)
					(thickness 0.15)
				)
				(justify right)
			)
		)
		(property "Value" "R_470R_0402"
			(at 372.11 17.78 0)
			(effects
				(font
					(size 1.27 1.27)
					(thickness 0.15)
				)
				(justify left bottom)
				(hide yes)
			)
		)
		(property "Footprint" "antmicro-footprints:R_0402_1005Metric"
			(at 374.65 17.78 0)
			(effects
				(font
					(size 1.27 1.27)
					(thickness 0.15)
				)
				(justify left bottom)
				(hide yes)
			)
		)
		(property "Datasheet" "https://www.bourns.com/docs/product-datasheets/cr.pdf"
			(at 377.19 17.78 0)
			(effects
				(font
					(size 1.27 1.27)
					(thickness 0.15)
				)
				(justify left bottom)
				(hide yes)
			)
		)
		(property "Description" "SMD Chip Resistor, 470 ohm, ± 1%, 62.5 mW, 0402 [1005 Metric], Thick Film, General Purpose"
			(at 359.41 38.1 0)
			(effects
				(font
					(size 1.27 1.27)
				)
				(hide yes)
			)
		)
		(property "MPN" "CR0402-FX-4700GLF"
			(at 379.73 17.78 0)
			(effects
				(font
					(size 1.27 1.27)
					(thickness 0.15)
				)
				(justify left bottom)
				(hide yes)
			)
		)
		(property "Manufacturer" "Bourns"
			(at 382.27 17.78 0)
			(effects
				(font
					(size 1.27 1.27)
					(thickness 0.15)
				)
				(justify left bottom)
				(hide yes)
			)
		)
		(property "License" "Apache-2.0"
			(at 384.81 17.78 0)
			(effects
				(font
					(size 1.27 1.27)
					(thickness 0.15)
				)
				(justify left bottom)
				(hide yes)
			)
		)
		(property "Author" "Antmicro"
			(at 387.35 17.78 0)
			(effects
				(font
					(size 1.27 1.27)
					(thickness 0.15)
				)
				(justify left bottom)
				(hide yes)
			)
		)
		(property "Val" "470R"
			(at 361.95 36.83 90)
			(effects
				(font
					(size 1.27 1.27)
					(thickness 0.15)
				)
				(justify right)
			)
		)
		(property "Tolerance" "1%"
			(at 369.57 17.78 0)
			(effects
				(font
					(size 1.27 1.27)
				)
				(justify left bottom)
				(hide yes)
			)
		)
		(pin "2"
		)
		(pin "1"
		)
		(instances
			(project "usb_debug_pd"
				(path ""
					(reference "R?")
					(unit 1)
				)
			)
			(project "jetson-agx-thor-baseboard"
				(path ""
					(reference "R156")
					(unit 1)
				)
			)
		)
	)
	(symbol
		(lib_id "antmicropower:GND")
		(at 321.31 133.35 0)
		(mirror y)
		(unit 1)
		(exclude_from_sim no)
		(in_bom yes)
		(on_board yes)
		(dnp no)
		(property "Reference" "#PWR0286"
			(at 321.31 139.7 0)
			(effects
				(font
					(size 1.27 1.27)
				)
				(justify left bottom)
				(hide yes)
			)
		)
		(property "Value" "GND"
			(at 321.31 137.16 0)
			(effects
				(font
					(size 1.27 1.27)
					(thickness 0.15)
				)
			)
		)
		(property "Footprint" ""
			(at 312.42 140.97 0)
			(effects
				(font
					(size 1.27 1.27)
					(thickness 0.15)
				)
				(justify left bottom)
				(hide yes)
			)
		)
		(property "Datasheet" ""
			(at 312.42 146.05 0)
			(effects
				(font
					(size 1.27 1.27)
					(thickness 0.15)
				)
				(justify left bottom)
				(hide yes)
			)
		)
		(property "Description" ""
			(at 321.31 133.35 0)
			(effects
				(font
					(size 1.27 1.27)
				)
				(hide yes)
			)
		)
		(property "Author" "Antmicro"
			(at 312.42 140.97 0)
			(effects
				(font
					(size 1.27 1.27)
					(thickness 0.15)
				)
				(justify left bottom)
				(hide yes)
			)
		)
		(property "License" "Apache-2.0"
			(at 312.42 143.51 0)
			(effects
				(font
					(size 1.27 1.27)
					(thickness 0.15)
				)
				(justify left bottom)
				(hide yes)
			)
		)
		(pin "1"
		)
		(instances
			(project "usb_debug_pd"
				(path ""
					(reference "#PWR?")
					(unit 1)
				)
			)
			(project "jetson-agx-thor-baseboard"
				(path ""
					(reference "#PWR0286")
					(unit 1)
				)
			)
		)
	)
	(symbol
		(lib_id "antmicroResistors0402:R_4k7_0402")
		(at 234.95 222.25 270)
		(unit 1)
		(exclude_from_sim no)
		(in_bom yes)
		(on_board yes)
		(dnp no)
		(property "Reference" "R225"
			(at 234.442 222.758 0)
			(effects
				(font
					(size 1.27 1.27)
				)
				(justify right top)
			)
		)
		(property "Value" "R_4k7_0402"
			(at 222.25 242.57 0)
			(effects
				(font
					(size 1.27 1.27)
					(thickness 0.15)
				)
				(justify left bottom)
				(hide yes)
			)
		)
		(property "Footprint" "antmicro-footprints:R_0402_1005Metric"
			(at 219.71 242.57 0)
			(effects
				(font
					(size 1.27 1.27)
					(thickness 0.15)
				)
				(justify left bottom)
				(hide yes)
			)
		)
		(property "Datasheet" "https://www.bourns.com/docs/product-datasheets/cr.pdf"
			(at 217.17 242.57 0)
			(effects
				(font
					(size 1.27 1.27)
					(thickness 0.15)
				)
				(justify left bottom)
				(hide yes)
			)
		)
		(property "Description" "SMD Chip Resistor, 4.7 kohm, ± 1%, 62.5 mW, 0402 [1005 Metric], Thick Film, General Purpose"
			(at 234.95 222.25 0)
			(effects
				(font
					(size 1.27 1.27)
				)
				(hide yes)
			)
		)
		(property "Manufacturer" "Bourns"
			(at 212.09 242.57 0)
			(effects
				(font
					(size 1.27 1.27)
					(thickness 0.15)
				)
				(justify left bottom)
				(hide yes)
			)
		)
		(property "MPN" "CR0402-FX-4701GLF"
			(at 214.63 242.57 0)
			(effects
				(font
					(size 1.27 1.27)
					(thickness 0.15)
				)
				(justify left bottom)
				(hide yes)
			)
		)
		(property "Val" "4k7"
			(at 234.315 231.14 0)
			(effects
				(font
					(size 1.27 1.27)
					(thickness 0.15)
				)
				(justify right top)
			)
		)
		(property "License" "Apache-2.0"
			(at 209.55 242.57 0)
			(effects
				(font
					(size 1.27 1.27)
					(thickness 0.15)
				)
				(justify left bottom)
				(hide yes)
			)
		)
		(property "Author" "Antmicro"
			(at 207.01 242.57 0)
			(effects
				(font
					(size 1.27 1.27)
					(thickness 0.15)
				)
				(justify left bottom)
				(hide yes)
			)
		)
		(property "Tolerance" "1%"
			(at 224.79 242.57 0)
			(effects
				(font
					(size 1.27 1.27)
				)
				(justify left bottom)
				(hide yes)
			)
		)
		(pin "1"
		)
		(pin "2"
		)
		(instances
			(project "jetson-agx-thor-baseboard"
				(path ""
					(reference "R225")
					(unit 1)
				)
			)
		)
	)
	(symbol
		(lib_id "antmicroCapacitorsmisc:C_22u_25V_0805")
		(at 73.66 66.04 90)
		(mirror x)
		(unit 1)
		(exclude_from_sim no)
		(in_bom yes)
		(on_board yes)
		(dnp no)
		(fields_autoplaced yes)
		(property "Reference" "C123"
			(at 71.12 66.0462 90)
			(effects
				(font
					(size 1.27 1.27)
				)
				(justify left)
			)
		)
		(property "Value" "C_22u_25V_0805"
			(at 83.82 86.36 0)
			(effects
				(font
					(size 1.27 1.27)
					(thickness 0.15)
				)
				(justify left bottom)
				(hide yes)
			)
		)
		(property "Footprint" "antmicro-footprints:C_0805_2012Metric"
			(at 86.36 86.36 0)
			(effects
				(font
					(size 1.27 1.27)
					(thickness 0.15)
				)
				(justify left bottom)
				(hide yes)
			)
		)
		(property "Datasheet" "https://product.samsungsem.com/mlcc/CL21A226MAYNNN.do"
			(at 88.9 86.36 0)
			(effects
				(font
					(size 1.27 1.27)
					(thickness 0.15)
				)
				(justify left bottom)
				(hide yes)
			)
		)
		(property "Description" "SMT Multilayer Ceramic Capacitor, 22uF, +/-20%, 25V, X5R, 0805 [2012 Metric]"
			(at 73.66 66.04 0)
			(effects
				(font
					(size 1.27 1.27)
				)
				(hide yes)
			)
		)
		(property "Manufacturer" "Samsung Electro-Mechanics"
			(at 93.98 86.36 0)
			(effects
				(font
					(size 1.27 1.27)
					(thickness 0.15)
				)
				(justify left bottom)
				(hide yes)
			)
		)
		(property "MPN" "CL21A226MAYNNNE"
			(at 91.44 86.36 0)
			(effects
				(font
					(size 1.27 1.27)
					(thickness 0.15)
				)
				(justify left bottom)
				(hide yes)
			)
		)
		(property "Val" "22u"
			(at 71.12 68.5863 90)
			(effects
				(font
					(size 1.27 1.27)
					(thickness 0.15)
				)
				(justify left)
			)
		)
		(property "License" "Apache-2.0"
			(at 96.52 86.36 0)
			(effects
				(font
					(size 1.27 1.27)
					(thickness 0.15)
				)
				(justify left bottom)
				(hide yes)
			)
		)
		(property "Author" "Antmicro"
			(at 99.06 86.36 0)
			(effects
				(font
					(size 1.27 1.27)
					(thickness 0.15)
				)
				(justify left bottom)
				(hide yes)
			)
		)
		(property "Voltage" "25V"
			(at 71.12 71.1262 90)
			(effects
				(font
					(size 1.27 1.27)
				)
				(justify left)
			)
		)
		(property "Dielectric" "X5R"
			(at 104.14 86.36 0)
			(effects
				(font
					(size 1.27 1.27)
				)
				(justify left bottom)
				(hide yes)
			)
		)
		(property "Public" "False"
			(at 106.68 86.36 0)
			(effects
				(font
					(size 1.27 1.27)
				)
				(justify left bottom)
				(hide yes)
			)
		)
		(pin "1"
		)
		(pin "2"
		)
		(instances
			(project "usb_debug_pd"
				(path ""
					(reference "C?")
					(unit 1)
				)
			)
			(project "jetson-agx-thor-baseboard"
				(path ""
					(reference "C123")
					(unit 1)
				)
			)
		)
	)
	(symbol
		(lib_id "antmicroResistors0402:R_200R_0402")
		(at 255.27 236.22 0)
		(unit 1)
		(exclude_from_sim no)
		(in_bom yes)
		(on_board yes)
		(dnp no)
		(property "Reference" "R109"
			(at 260.35 235.585 0)
			(effects
				(font
					(size 1.27 1.27)
				)
				(justify left bottom)
			)
		)
		(property "Value" "R_200R_0402"
			(at 275.59 248.92 0)
			(effects
				(font
					(size 1.27 1.27)
					(thickness 0.15)
				)
				(justify left bottom)
				(hide yes)
			)
		)
		(property "Footprint" "antmicro-footprints:R_0402_1005Metric"
			(at 275.59 251.46 0)
			(effects
				(font
					(size 1.27 1.27)
					(thickness 0.15)
				)
				(justify left bottom)
				(hide yes)
			)
		)
		(property "Datasheet" "https://www.bourns.com/docs/product-datasheets/cr.pdf"
			(at 275.59 254 0)
			(effects
				(font
					(size 1.27 1.27)
					(thickness 0.15)
				)
				(justify left bottom)
				(hide yes)
			)
		)
		(property "Description" "SMD Chip Resistor, 200 ohm, ± 1%, 62.5 mW, 0402 [1005 Metric], Thick Film, General Purpose"
			(at 255.27 236.22 0)
			(effects
				(font
					(size 1.27 1.27)
				)
				(hide yes)
			)
		)
		(property "Manufacturer" "Bourns"
			(at 275.59 259.08 0)
			(effects
				(font
					(size 1.27 1.27)
					(thickness 0.15)
				)
				(justify left bottom)
				(hide yes)
			)
		)
		(property "MPN" "CR0402-FX-2000GLF"
			(at 275.59 256.54 0)
			(effects
				(font
					(size 1.27 1.27)
					(thickness 0.15)
				)
				(justify left bottom)
				(hide yes)
			)
		)
		(property "Val" "200R"
			(at 250.19 235.585 0)
			(effects
				(font
					(size 1.27 1.27)
					(thickness 0.15)
				)
				(justify left bottom)
			)
		)
		(property "License" "Apache-2.0"
			(at 275.59 261.62 0)
			(effects
				(font
					(size 1.27 1.27)
					(thickness 0.15)
				)
				(justify left bottom)
				(hide yes)
			)
		)
		(property "Author" "Antmicro"
			(at 275.59 264.16 0)
			(effects
				(font
					(size 1.27 1.27)
					(thickness 0.15)
				)
				(justify left bottom)
				(hide yes)
			)
		)
		(property "Tolerance" "1%"
			(at 275.59 246.38 0)
			(effects
				(font
					(size 1.27 1.27)
				)
				(justify left bottom)
				(hide yes)
			)
		)
		(pin "1"
		)
		(pin "2"
		)
		(instances
			(project "usb_debug_pd"
				(path ""
					(reference "R?")
					(unit 1)
				)
			)
			(project "jetson-agx-thor-baseboard"
				(path ""
					(reference "R109")
					(unit 1)
				)
			)
		)
	)
	(symbol
		(lib_id "antmicropower:GND")
		(at 214.63 82.55 0)
		(mirror y)
		(unit 1)
		(exclude_from_sim no)
		(in_bom yes)
		(on_board yes)
		(dnp no)
		(property "Reference" "#PWR0263"
			(at 214.63 88.9 0)
			(effects
				(font
					(size 1.27 1.27)
				)
				(justify left bottom)
				(hide yes)
			)
		)
		(property "Value" "GND"
			(at 214.63 86.36 0)
			(effects
				(font
					(size 1.27 1.27)
					(thickness 0.15)
				)
			)
		)
		(property "Footprint" ""
			(at 205.74 90.17 0)
			(effects
				(font
					(size 1.27 1.27)
					(thickness 0.15)
				)
				(justify left bottom)
				(hide yes)
			)
		)
		(property "Datasheet" ""
			(at 205.74 95.25 0)
			(effects
				(font
					(size 1.27 1.27)
					(thickness 0.15)
				)
				(justify left bottom)
				(hide yes)
			)
		)
		(property "Description" ""
			(at 214.63 82.55 0)
			(effects
				(font
					(size 1.27 1.27)
				)
				(hide yes)
			)
		)
		(property "Author" "Antmicro"
			(at 205.74 90.17 0)
			(effects
				(font
					(size 1.27 1.27)
					(thickness 0.15)
				)
				(justify left bottom)
				(hide yes)
			)
		)
		(property "License" "Apache-2.0"
			(at 205.74 92.71 0)
			(effects
				(font
					(size 1.27 1.27)
					(thickness 0.15)
				)
				(justify left bottom)
				(hide yes)
			)
		)
		(pin "1"
		)
		(instances
			(project "usb_debug_pd"
				(path ""
					(reference "#PWR?")
					(unit 1)
				)
			)
			(project "jetson-agx-thor-baseboard"
				(path ""
					(reference "#PWR0263")
					(unit 1)
				)
			)
		)
	)
	(symbol
		(lib_id "antmicroResistors0402:R_0R_0402")
		(at 157.48 101.6 0)
		(unit 1)
		(exclude_from_sim no)
		(in_bom yes)
		(on_board yes)
		(dnp no)
		(property "Reference" "R124"
			(at 157.48 100.965 0)
			(effects
				(font
					(size 1.27 1.27)
				)
				(justify right bottom)
			)
		)
		(property "Value" "R_0R_0402"
			(at 177.8 114.3 0)
			(effects
				(font
					(size 1.27 1.27)
					(thickness 0.15)
				)
				(justify left bottom)
				(hide yes)
			)
		)
		(property "Footprint" "antmicro-footprints:R_0402_1005Metric"
			(at 177.8 116.84 0)
			(effects
				(font
					(size 1.27 1.27)
					(thickness 0.15)
				)
				(justify left bottom)
				(hide yes)
			)
		)
		(property "Datasheet" "https://industrial.panasonic.com/cdbs/www-data/pdf/RDA0000/AOA0000C301.pdf"
			(at 177.8 119.38 0)
			(effects
				(font
					(size 1.27 1.27)
					(thickness 0.15)
				)
				(justify left bottom)
				(hide yes)
			)
		)
		(property "Description" "SMD Chip Resistor, Jumper, 0 ohm, 100 mW, 0402 [1005 Metric], Thick Film, General Purpose"
			(at 157.48 101.6 0)
			(effects
				(font
					(size 1.27 1.27)
				)
				(hide yes)
			)
		)
		(property "Manufacturer" "Panasonic"
			(at 177.8 124.46 0)
			(effects
				(font
					(size 1.27 1.27)
					(thickness 0.15)
				)
				(justify left bottom)
				(hide yes)
			)
		)
		(property "MPN" "ERJ2GE0R00X"
			(at 177.8 121.92 0)
			(effects
				(font
					(size 1.27 1.27)
					(thickness 0.15)
				)
				(justify left bottom)
				(hide yes)
			)
		)
		(property "Val" "0R"
			(at 165.1 100.965 0)
			(effects
				(font
					(size 1.27 1.27)
					(thickness 0.15)
				)
				(justify right bottom)
			)
		)
		(property "License" "Apache-2.0"
			(at 177.8 127 0)
			(effects
				(font
					(size 1.27 1.27)
					(thickness 0.15)
				)
				(justify left bottom)
				(hide yes)
			)
		)
		(property "Author" "Antmicro"
			(at 177.8 129.54 0)
			(effects
				(font
					(size 1.27 1.27)
					(thickness 0.15)
				)
				(justify left bottom)
				(hide yes)
			)
		)
		(property "Tolerance" "~"
			(at 177.8 111.76 0)
			(effects
				(font
					(size 1.27 1.27)
				)
				(justify left bottom)
				(hide yes)
			)
		)
		(property "Current" "1A"
			(at 177.8 132.08 0)
			(effects
				(font
					(size 1.27 1.27)
					(thickness 0.15)
				)
				(justify left bottom)
				(hide yes)
			)
		)
		(pin "1"
		)
		(pin "2"
		)
		(instances
			(project "usb_debug_pd"
				(path ""
					(reference "R?")
					(unit 1)
				)
			)
			(project "jetson-agx-thor-baseboard"
				(path ""
					(reference "R124")
					(unit 1)
				)
			)
		)
	)
	(symbol
		(lib_id "antmicroResistors0402:R_4k7_0402")
		(at 242.57 222.25 270)
		(unit 1)
		(exclude_from_sim no)
		(in_bom yes)
		(on_board yes)
		(dnp no)
		(property "Reference" "R105"
			(at 242.062 222.758 0)
			(effects
				(font
					(size 1.27 1.27)
				)
				(justify right top)
			)
		)
		(property "Value" "R_4k7_0402"
			(at 229.87 242.57 0)
			(effects
				(font
					(size 1.27 1.27)
					(thickness 0.15)
				)
				(justify left bottom)
				(hide yes)
			)
		)
		(property "Footprint" "antmicro-footprints:R_0402_1005Metric"
			(at 227.33 242.57 0)
			(effects
				(font
					(size 1.27 1.27)
					(thickness 0.15)
				)
				(justify left bottom)
				(hide yes)
			)
		)
		(property "Datasheet" "https://www.bourns.com/docs/product-datasheets/cr.pdf"
			(at 224.79 242.57 0)
			(effects
				(font
					(size 1.27 1.27)
					(thickness 0.15)
				)
				(justify left bottom)
				(hide yes)
			)
		)
		(property "Description" "SMD Chip Resistor, 4.7 kohm, ± 1%, 62.5 mW, 0402 [1005 Metric], Thick Film, General Purpose"
			(at 242.57 222.25 0)
			(effects
				(font
					(size 1.27 1.27)
				)
				(hide yes)
			)
		)
		(property "Manufacturer" "Bourns"
			(at 219.71 242.57 0)
			(effects
				(font
					(size 1.27 1.27)
					(thickness 0.15)
				)
				(justify left bottom)
				(hide yes)
			)
		)
		(property "MPN" "CR0402-FX-4701GLF"
			(at 222.25 242.57 0)
			(effects
				(font
					(size 1.27 1.27)
					(thickness 0.15)
				)
				(justify left bottom)
				(hide yes)
			)
		)
		(property "Val" "4k7"
			(at 241.935 231.14 0)
			(effects
				(font
					(size 1.27 1.27)
					(thickness 0.15)
				)
				(justify right top)
			)
		)
		(property "License" "Apache-2.0"
			(at 217.17 242.57 0)
			(effects
				(font
					(size 1.27 1.27)
					(thickness 0.15)
				)
				(justify left bottom)
				(hide yes)
			)
		)
		(property "Author" "Antmicro"
			(at 214.63 242.57 0)
			(effects
				(font
					(size 1.27 1.27)
					(thickness 0.15)
				)
				(justify left bottom)
				(hide yes)
			)
		)
		(property "Tolerance" "1%"
			(at 232.41 242.57 0)
			(effects
				(font
					(size 1.27 1.27)
				)
				(justify left bottom)
				(hide yes)
			)
		)
		(pin "1"
		)
		(pin "2"
		)
		(instances
			(project "usb_debug_pd"
				(path ""
					(reference "R?")
					(unit 1)
				)
			)
			(project "jetson-agx-thor-baseboard"
				(path ""
					(reference "R105")
					(unit 1)
				)
			)
		)
	)
	(symbol
		(lib_id "antmicroResistors0402:R_0R_0402")
		(at 261.62 247.65 180)
		(unit 1)
		(exclude_from_sim no)
		(in_bom yes)
		(on_board yes)
		(dnp no)
		(property "Reference" "R111"
			(at 261.62 247.015 0)
			(effects
				(font
					(size 1.27 1.27)
				)
				(justify right top)
			)
		)
		(property "Value" "R_0R_0402"
			(at 241.3 234.95 0)
			(effects
				(font
					(size 1.27 1.27)
					(thickness 0.15)
				)
				(justify left bottom)
				(hide yes)
			)
		)
		(property "Footprint" "antmicro-footprints:R_0402_1005Metric"
			(at 241.3 232.41 0)
			(effects
				(font
					(size 1.27 1.27)
					(thickness 0.15)
				)
				(justify left bottom)
				(hide yes)
			)
		)
		(property "Datasheet" "https://industrial.panasonic.com/cdbs/www-data/pdf/RDA0000/AOA0000C301.pdf"
			(at 241.3 229.87 0)
			(effects
				(font
					(size 1.27 1.27)
					(thickness 0.15)
				)
				(justify left bottom)
				(hide yes)
			)
		)
		(property "Description" "SMD Chip Resistor, Jumper, 0 ohm, 100 mW, 0402 [1005 Metric], Thick Film, General Purpose"
			(at 261.62 247.65 0)
			(effects
				(font
					(size 1.27 1.27)
				)
				(hide yes)
			)
		)
		(property "Manufacturer" "Panasonic"
			(at 241.3 224.79 0)
			(effects
				(font
					(size 1.27 1.27)
					(thickness 0.15)
				)
				(justify left bottom)
				(hide yes)
			)
		)
		(property "MPN" "ERJ2GE0R00X"
			(at 241.3 227.33 0)
			(effects
				(font
					(size 1.27 1.27)
					(thickness 0.15)
				)
				(justify left bottom)
				(hide yes)
			)
		)
		(property "Val" "0R"
			(at 254 247.015 0)
			(effects
				(font
					(size 1.27 1.27)
					(thickness 0.15)
				)
				(justify right top)
			)
		)
		(property "License" "Apache-2.0"
			(at 241.3 222.25 0)
			(effects
				(font
					(size 1.27 1.27)
					(thickness 0.15)
				)
				(justify left bottom)
				(hide yes)
			)
		)
		(property "Author" "Antmicro"
			(at 241.3 219.71 0)
			(effects
				(font
					(size 1.27 1.27)
					(thickness 0.15)
				)
				(justify left bottom)
				(hide yes)
			)
		)
		(property "Tolerance" "~"
			(at 241.3 237.49 0)
			(effects
				(font
					(size 1.27 1.27)
				)
				(justify left bottom)
				(hide yes)
			)
		)
		(property "Current" "1A"
			(at 241.3 217.17 0)
			(effects
				(font
					(size 1.27 1.27)
					(thickness 0.15)
				)
				(justify left bottom)
				(hide yes)
			)
		)
		(pin "1"
		)
		(pin "2"
		)
		(instances
			(project "usb_debug_pd"
				(path ""
					(reference "R?")
					(unit 1)
				)
			)
			(project "jetson-agx-thor-baseboard"
				(path ""
					(reference "R111")
					(unit 1)
				)
			)
		)
	)
	(symbol
		(lib_id "antmicroResistors0402:R_0R_0402")
		(at 274.32 36.83 0)
		(unit 1)
		(exclude_from_sim no)
		(in_bom yes)
		(on_board yes)
		(dnp no)
		(property "Reference" "R151"
			(at 279.4 36.195 0)
			(effects
				(font
					(size 1.27 1.27)
				)
				(justify left bottom)
			)
		)
		(property "Value" "R_0R_0402"
			(at 294.64 49.53 0)
			(effects
				(font
					(size 1.27 1.27)
					(thickness 0.15)
				)
				(justify left bottom)
				(hide yes)
			)
		)
		(property "Footprint" "antmicro-footprints:R_0402_1005Metric"
			(at 294.64 52.07 0)
			(effects
				(font
					(size 1.27 1.27)
					(thickness 0.15)
				)
				(justify left bottom)
				(hide yes)
			)
		)
		(property "Datasheet" "https://industrial.panasonic.com/cdbs/www-data/pdf/RDA0000/AOA0000C301.pdf"
			(at 294.64 54.61 0)
			(effects
				(font
					(size 1.27 1.27)
					(thickness 0.15)
				)
				(justify left bottom)
				(hide yes)
			)
		)
		(property "Description" "SMD Chip Resistor, Jumper, 0 ohm, 100 mW, 0402 [1005 Metric], Thick Film, General Purpose"
			(at 274.32 36.83 0)
			(effects
				(font
					(size 1.27 1.27)
				)
				(hide yes)
			)
		)
		(property "Manufacturer" "Panasonic"
			(at 294.64 59.69 0)
			(effects
				(font
					(size 1.27 1.27)
					(thickness 0.15)
				)
				(justify left bottom)
				(hide yes)
			)
		)
		(property "MPN" "ERJ2GE0R00X"
			(at 294.64 57.15 0)
			(effects
				(font
					(size 1.27 1.27)
					(thickness 0.15)
				)
				(justify left bottom)
				(hide yes)
			)
		)
		(property "Val" "0R"
			(at 271.78 36.195 0)
			(effects
				(font
					(size 1.27 1.27)
					(thickness 0.15)
				)
				(justify left bottom)
			)
		)
		(property "License" "Apache-2.0"
			(at 294.64 62.23 0)
			(effects
				(font
					(size 1.27 1.27)
					(thickness 0.15)
				)
				(justify left bottom)
				(hide yes)
			)
		)
		(property "Author" "Antmicro"
			(at 294.64 64.77 0)
			(effects
				(font
					(size 1.27 1.27)
					(thickness 0.15)
				)
				(justify left bottom)
				(hide yes)
			)
		)
		(property "Tolerance" "~"
			(at 294.64 46.99 0)
			(effects
				(font
					(size 1.27 1.27)
				)
				(justify left bottom)
				(hide yes)
			)
		)
		(property "Current" "1A"
			(at 294.64 67.31 0)
			(effects
				(font
					(size 1.27 1.27)
					(thickness 0.15)
				)
				(justify left bottom)
				(hide yes)
			)
		)
		(pin "1"
		)
		(pin "2"
		)
		(instances
			(project "usb_debug_pd"
				(path ""
					(reference "R?")
					(unit 1)
				)
			)
			(project "jetson-agx-thor-baseboard"
				(path ""
					(reference "R151")
					(unit 1)
				)
			)
		)
	)
	(symbol
		(lib_id "antmicropower:GND")
		(at 144.78 72.39 0)
		(unit 1)
		(exclude_from_sim no)
		(in_bom yes)
		(on_board yes)
		(dnp no)
		(property "Reference" "#PWR0245"
			(at 144.78 78.74 0)
			(effects
				(font
					(size 1.27 1.27)
				)
				(justify left bottom)
				(hide yes)
			)
		)
		(property "Value" "GND"
			(at 144.78 76.2 0)
			(effects
				(font
					(size 1.27 1.27)
					(thickness 0.15)
				)
			)
		)
		(property "Footprint" ""
			(at 153.67 80.01 0)
			(effects
				(font
					(size 1.27 1.27)
					(thickness 0.15)
				)
				(justify left bottom)
				(hide yes)
			)
		)
		(property "Datasheet" ""
			(at 153.67 85.09 0)
			(effects
				(font
					(size 1.27 1.27)
					(thickness 0.15)
				)
				(justify left bottom)
				(hide yes)
			)
		)
		(property "Description" ""
			(at 144.78 72.39 0)
			(effects
				(font
					(size 1.27 1.27)
				)
				(hide yes)
			)
		)
		(property "Author" "Antmicro"
			(at 153.67 80.01 0)
			(effects
				(font
					(size 1.27 1.27)
					(thickness 0.15)
				)
				(justify left bottom)
				(hide yes)
			)
		)
		(property "License" "Apache-2.0"
			(at 153.67 82.55 0)
			(effects
				(font
					(size 1.27 1.27)
					(thickness 0.15)
				)
				(justify left bottom)
				(hide yes)
			)
		)
		(pin "1"
		)
		(instances
			(project "usb_debug_pd"
				(path ""
					(reference "#PWR?")
					(unit 1)
				)
			)
			(project "jetson-agx-thor-baseboard"
				(path ""
					(reference "#PWR0245")
					(unit 1)
				)
			)
		)
	)
	(symbol
		(lib_id "antmicroCapacitors0402:C_100n_0402")
		(at 144.78 66.04 270)
		(unit 1)
		(exclude_from_sim no)
		(in_bom yes)
		(on_board yes)
		(dnp no)
		(fields_autoplaced yes)
		(property "Reference" "C134"
			(at 142.24 67.3163 90)
			(effects
				(font
					(size 1.27 1.27)
				)
				(justify right)
			)
		)
		(property "Value" "C_100n_0402"
			(at 134.62 86.36 0)
			(effects
				(font
					(size 1.27 1.27)
					(thickness 0.15)
				)
				(justify left bottom)
				(hide yes)
			)
		)
		(property "Footprint" "antmicro-footprints:C_0402_1005Metric"
			(at 132.08 86.36 0)
			(effects
				(font
					(size 1.27 1.27)
					(thickness 0.15)
				)
				(justify left bottom)
				(hide yes)
			)
		)
		(property "Datasheet" "https://www.murata.com/products/productdetail?partno=GRM155R61H104KE14%23"
			(at 129.54 86.36 0)
			(effects
				(font
					(size 1.27 1.27)
					(thickness 0.15)
				)
				(justify left bottom)
				(hide yes)
			)
		)
		(property "Description" "SMD Multilayer Ceramic Capacitor, 0.1 µF, 50 V, 0402 [1005 Metric], ± 10%, X5R, GRM Series"
			(at 144.78 66.04 0)
			(effects
				(font
					(size 1.27 1.27)
				)
				(hide yes)
			)
		)
		(property "Manufacturer" "Murata"
			(at 124.46 86.36 0)
			(effects
				(font
					(size 1.27 1.27)
					(thickness 0.15)
				)
				(justify left bottom)
				(hide yes)
			)
		)
		(property "MPN" "GRM155R61H104KE14D"
			(at 127 86.36 0)
			(effects
				(font
					(size 1.27 1.27)
					(thickness 0.15)
				)
				(justify left bottom)
				(hide yes)
			)
		)
		(property "Val" "100n"
			(at 142.24 69.8563 90)
			(effects
				(font
					(size 1.27 1.27)
					(thickness 0.15)
				)
				(justify right)
			)
		)
		(property "License" "Apache-2.0"
			(at 121.92 86.36 0)
			(effects
				(font
					(size 1.27 1.27)
					(thickness 0.15)
				)
				(justify left bottom)
				(hide yes)
			)
		)
		(property "Author" "Antmicro"
			(at 119.38 86.36 0)
			(effects
				(font
					(size 1.27 1.27)
					(thickness 0.15)
				)
				(justify left bottom)
				(hide yes)
			)
		)
		(property "Voltage" "50V"
			(at 116.84 86.36 0)
			(effects
				(font
					(size 1.27 1.27)
				)
				(justify left bottom)
				(hide yes)
			)
		)
		(property "Dielectric" "X5R"
			(at 114.3 86.36 0)
			(effects
				(font
					(size 1.27 1.27)
				)
				(justify left bottom)
				(hide yes)
			)
		)
		(pin "1"
		)
		(pin "2"
		)
		(instances
			(project "usb_debug_pd"
				(path ""
					(reference "C?")
					(unit 1)
				)
			)
			(project "jetson-agx-thor-baseboard"
				(path ""
					(reference "C134")
					(unit 1)
				)
			)
		)
	)
	(symbol
		(lib_id "antmicropower:GND")
		(at 109.22 72.39 0)
		(mirror y)
		(unit 1)
		(exclude_from_sim no)
		(in_bom yes)
		(on_board yes)
		(dnp no)
		(property "Reference" "#PWR0241"
			(at 109.22 78.74 0)
			(effects
				(font
					(size 1.27 1.27)
				)
				(justify left bottom)
				(hide yes)
			)
		)
		(property "Value" "GND"
			(at 109.22 76.2 0)
			(effects
				(font
					(size 1.27 1.27)
					(thickness 0.15)
				)
			)
		)
		(property "Footprint" ""
			(at 100.33 80.01 0)
			(effects
				(font
					(size 1.27 1.27)
					(thickness 0.15)
				)
				(justify left bottom)
				(hide yes)
			)
		)
		(property "Datasheet" ""
			(at 100.33 85.09 0)
			(effects
				(font
					(size 1.27 1.27)
					(thickness 0.15)
				)
				(justify left bottom)
				(hide yes)
			)
		)
		(property "Description" ""
			(at 109.22 72.39 0)
			(effects
				(font
					(size 1.27 1.27)
				)
				(hide yes)
			)
		)
		(property "Author" "Antmicro"
			(at 100.33 80.01 0)
			(effects
				(font
					(size 1.27 1.27)
					(thickness 0.15)
				)
				(justify left bottom)
				(hide yes)
			)
		)
		(property "License" "Apache-2.0"
			(at 100.33 82.55 0)
			(effects
				(font
					(size 1.27 1.27)
					(thickness 0.15)
				)
				(justify left bottom)
				(hide yes)
			)
		)
		(pin "1"
		)
		(instances
			(project "usb_debug_pd"
				(path ""
					(reference "#PWR?")
					(unit 1)
				)
			)
			(project "jetson-agx-thor-baseboard"
				(path ""
					(reference "#PWR0241")
					(unit 1)
				)
			)
		)
	)
	(symbol
		(lib_id "antmicroResistors0402:R_4k7_0402")
		(at 237.49 222.25 270)
		(unit 1)
		(exclude_from_sim no)
		(in_bom no)
		(on_board yes)
		(dnp yes)
		(property "Reference" "R103"
			(at 236.982 222.758 0)
			(effects
				(font
					(size 1.27 1.27)
				)
				(justify right top)
			)
		)
		(property "Value" "R_4k7_0402"
			(at 224.79 242.57 0)
			(effects
				(font
					(size 1.27 1.27)
					(thickness 0.15)
				)
				(justify left bottom)
				(hide yes)
			)
		)
		(property "Footprint" "antmicro-footprints:R_0402_1005Metric"
			(at 222.25 242.57 0)
			(effects
				(font
					(size 1.27 1.27)
					(thickness 0.15)
				)
				(justify left bottom)
				(hide yes)
			)
		)
		(property "Datasheet" "https://www.bourns.com/docs/product-datasheets/cr.pdf"
			(at 219.71 242.57 0)
			(effects
				(font
					(size 1.27 1.27)
					(thickness 0.15)
				)
				(justify left bottom)
				(hide yes)
			)
		)
		(property "Description" "SMD Chip Resistor, 4.7 kohm, ± 1%, 62.5 mW, 0402 [1005 Metric], Thick Film, General Purpose"
			(at 237.49 222.25 0)
			(effects
				(font
					(size 1.27 1.27)
				)
				(hide yes)
			)
		)
		(property "Manufacturer" "Bourns"
			(at 214.63 242.57 0)
			(effects
				(font
					(size 1.27 1.27)
					(thickness 0.15)
				)
				(justify left bottom)
				(hide yes)
			)
		)
		(property "MPN" "CR0402-FX-4701GLF"
			(at 217.17 242.57 0)
			(effects
				(font
					(size 1.27 1.27)
					(thickness 0.15)
				)
				(justify left bottom)
				(hide yes)
			)
		)
		(property "Val" "4k7"
			(at 236.855 231.14 0)
			(effects
				(font
					(size 1.27 1.27)
					(thickness 0.15)
				)
				(justify right top)
			)
		)
		(property "License" "Apache-2.0"
			(at 212.09 242.57 0)
			(effects
				(font
					(size 1.27 1.27)
					(thickness 0.15)
				)
				(justify left bottom)
				(hide yes)
			)
		)
		(property "Author" "Antmicro"
			(at 209.55 242.57 0)
			(effects
				(font
					(size 1.27 1.27)
					(thickness 0.15)
				)
				(justify left bottom)
				(hide yes)
			)
		)
		(property "Tolerance" "1%"
			(at 227.33 242.57 0)
			(effects
				(font
					(size 1.27 1.27)
				)
				(justify left bottom)
				(hide yes)
			)
		)
		(pin "1"
		)
		(pin "2"
		)
		(instances
			(project "usb_debug_pd"
				(path ""
					(reference "R?")
					(unit 1)
				)
			)
			(project "jetson-agx-thor-baseboard"
				(path ""
					(reference "R103")
					(unit 1)
				)
			)
		)
	)
	(symbol
		(lib_id "antmicroTransistorsFETsMOSFETsSingle:DMG1012T-7")
		(at 80.01 137.16 0)
		(unit 1)
		(exclude_from_sim no)
		(in_bom yes)
		(on_board yes)
		(dnp no)
		(property "Reference" "Q3"
			(at 60.96 131.064 0)
			(effects
				(font
					(size 1.27 1.27)
					(thickness 0.15)
				)
				(justify left)
			)
		)
		(property "Value" "DMG1012T-7"
			(at 102.87 146.05 0)
			(effects
				(font
					(size 1.27 1.27)
					(thickness 0.15)
				)
				(justify left bottom)
				(hide yes)
			)
		)
		(property "Footprint" "antmicro-footprints:SOT-523"
			(at 102.87 148.59 0)
			(effects
				(font
					(size 1.27 1.27)
					(thickness 0.15)
				)
				(justify left bottom)
				(hide yes)
			)
		)
		(property "Datasheet" "https://www.diodes.com/assets/Datasheets/ds31783.pdf"
			(at 102.87 151.13 0)
			(effects
				(font
					(size 1.27 1.27)
					(thickness 0.15)
				)
				(justify left bottom)
				(hide yes)
			)
		)
		(property "Description" "Power MOSFET, N Channel, 20 V, 630 mA, 0.3 ohm, SOT-523, Surface Mount"
			(at 102.87 163.83 0)
			(effects
				(font
					(size 1.27 1.27)
				)
				(justify left bottom)
				(hide yes)
			)
		)
		(property "MPN" "DMG1012T-7"
			(at 60.96 133.604 0)
			(effects
				(font
					(size 1.27 1.27)
					(thickness 0.15)
				)
				(justify left)
			)
		)
		(property "Manufacturer" "Diodes Incorporated"
			(at 102.87 156.21 0)
			(effects
				(font
					(size 1.27 1.27)
					(thickness 0.15)
				)
				(justify left bottom)
				(hide yes)
			)
		)
		(property "Author" "Antmicro"
			(at 102.87 158.75 0)
			(effects
				(font
					(size 1.27 1.27)
					(thickness 0.15)
				)
				(justify left bottom)
				(hide yes)
			)
		)
		(property "License" "Apache-2.0"
			(at 102.87 161.29 0)
			(effects
				(font
					(size 1.27 1.27)
					(thickness 0.15)
				)
				(justify left bottom)
				(hide yes)
			)
		)
		(pin "2"
		)
		(pin "3"
		)
		(pin "1"
		)
		(instances
			(project "usb_debug_pd"
				(path ""
					(reference "Q?")
					(unit 1)
				)
			)
			(project ""
				(path ""
					(reference "Q3")
					(unit 1)
				)
			)
		)
	)
	(symbol
		(lib_id "antmicroResistors0402:R_0R_0402")
		(at 55.88 232.41 0)
		(unit 1)
		(exclude_from_sim no)
		(in_bom no)
		(on_board yes)
		(dnp yes)
		(property "Reference" "R99"
			(at 62.992 231.14 0)
			(effects
				(font
					(size 1.27 1.27)
					(thickness 0.15)
				)
			)
		)
		(property "Value" "R_0R_0402"
			(at 76.2 245.11 0)
			(effects
				(font
					(size 1.27 1.27)
					(thickness 0.15)
				)
				(justify left bottom)
				(hide yes)
			)
		)
		(property "Footprint" "antmicro-footprints:R_0402_1005Metric"
			(at 76.2 247.65 0)
			(effects
				(font
					(size 1.27 1.27)
					(thickness 0.15)
				)
				(justify left bottom)
				(hide yes)
			)
		)
		(property "Datasheet" "https://industrial.panasonic.com/cdbs/www-data/pdf/RDA0000/AOA0000C301.pdf"
			(at 76.2 250.19 0)
			(effects
				(font
					(size 1.27 1.27)
					(thickness 0.15)
				)
				(justify left bottom)
				(hide yes)
			)
		)
		(property "Description" "SMD Chip Resistor, Jumper, 0 ohm, 100 mW, 0402 [1005 Metric], Thick Film, General Purpose"
			(at 76.2 265.43 0)
			(effects
				(font
					(size 1.27 1.27)
				)
				(justify left bottom)
				(hide yes)
			)
		)
		(property "MPN" "ERJ2GE0R00X"
			(at 76.2 252.73 0)
			(effects
				(font
					(size 1.27 1.27)
					(thickness 0.15)
				)
				(justify left bottom)
				(hide yes)
			)
		)
		(property "Manufacturer" "Panasonic"
			(at 76.2 255.27 0)
			(effects
				(font
					(size 1.27 1.27)
					(thickness 0.15)
				)
				(justify left bottom)
				(hide yes)
			)
		)
		(property "License" "Apache-2.0"
			(at 76.2 257.81 0)
			(effects
				(font
					(size 1.27 1.27)
					(thickness 0.15)
				)
				(justify left bottom)
				(hide yes)
			)
		)
		(property "Author" "Antmicro"
			(at 76.2 260.35 0)
			(effects
				(font
					(size 1.27 1.27)
					(thickness 0.15)
				)
				(justify left bottom)
				(hide yes)
			)
		)
		(property "Val" "0R"
			(at 55.118 231.14 0)
			(effects
				(font
					(size 1.27 1.27)
					(thickness 0.15)
				)
			)
		)
		(property "Tolerance" "~"
			(at 76.2 242.57 0)
			(effects
				(font
					(size 1.27 1.27)
				)
				(justify left bottom)
				(hide yes)
			)
		)
		(property "Current" "1A"
			(at 76.2 262.89 0)
			(effects
				(font
					(size 1.27 1.27)
					(thickness 0.15)
				)
				(justify left bottom)
				(hide yes)
			)
		)
		(pin "2"
		)
		(pin "1"
		)
		(instances
			(project "jetson-agx-thor-baseboard"
				(path ""
					(reference "R99")
					(unit 1)
				)
			)
		)
	)
	(symbol
		(lib_id "antmicroTestPoints:TP_0.75mm_SMD")
		(at 35.56 114.3 180)
		(unit 1)
		(exclude_from_sim no)
		(in_bom no)
		(on_board yes)
		(dnp no)
		(property "Reference" "TP91"
			(at 31.242 114.3 0)
			(effects
				(font
					(size 1.27 1.27)
					(thickness 0.15)
				)
				(justify left)
			)
		)
		(property "Value" "TP_0.75mm_SMD"
			(at 25.4 110.49 0)
			(effects
				(font
					(size 1.27 1.27)
					(thickness 0.15)
				)
				(justify left bottom)
				(hide yes)
			)
		)
		(property "Footprint" "antmicro-footprints:TP_SMD_0.75mm"
			(at 25.4 107.95 0)
			(effects
				(font
					(size 1.27 1.27)
					(thickness 0.15)
				)
				(justify left bottom)
				(hide yes)
			)
		)
		(property "Datasheet" ""
			(at 17.78 101.6 0)
			(effects
				(font
					(size 1.27 1.27)
					(thickness 0.15)
				)
				(justify left bottom)
				(hide yes)
			)
		)
		(property "Description" "SMT test point"
			(at 35.56 114.3 0)
			(effects
				(font
					(size 1.27 1.27)
				)
				(hide yes)
			)
		)
		(property "MPN" ""
			(at 24.765 102.87 0)
			(effects
				(font
					(size 1.27 1.27)
					(thickness 0.15)
				)
				(justify left bottom)
				(hide yes)
			)
		)
		(property "Manufacturer" ""
			(at 24.765 107.95 0)
			(effects
				(font
					(size 1.27 1.27)
					(thickness 0.15)
				)
				(justify left bottom)
				(hide yes)
			)
		)
		(property "Author" "Antmicro"
			(at 25.4 105.41 0)
			(effects
				(font
					(size 1.27 1.27)
					(thickness 0.15)
				)
				(justify left bottom)
				(hide yes)
			)
		)
		(property "License" "Apache-2.0"
			(at 25.4 102.87 0)
			(effects
				(font
					(size 1.27 1.27)
					(thickness 0.15)
				)
				(justify left bottom)
				(hide yes)
			)
		)
		(pin "1"
		)
		(instances
			(project "jetson-agx-thor-baseboard"
				(path ""
					(reference "TP91")
					(unit 1)
				)
			)
		)
	)
	(symbol
		(lib_id "antmicroResistors0402:R_1k_0402")
		(at 90.17 110.49 90)
		(unit 1)
		(exclude_from_sim no)
		(in_bom yes)
		(on_board yes)
		(dnp no)
		(property "Reference" "R114"
			(at 91.948 107.188 90)
			(effects
				(font
					(size 1.27 1.27)
					(thickness 0.15)
				)
				(justify right)
			)
		)
		(property "Value" "R_1k_0402"
			(at 102.87 90.17 0)
			(effects
				(font
					(size 1.27 1.27)
					(thickness 0.15)
				)
				(justify left bottom)
				(hide yes)
			)
		)
		(property "Footprint" "antmicro-footprints:R_0402_1005Metric"
			(at 105.41 90.17 0)
			(effects
				(font
					(size 1.27 1.27)
					(thickness 0.15)
				)
				(justify left bottom)
				(hide yes)
			)
		)
		(property "Datasheet" "https://www.bourns.com/docs/product-datasheets/cr.pdf"
			(at 107.95 90.17 0)
			(effects
				(font
					(size 1.27 1.27)
					(thickness 0.15)
				)
				(justify left bottom)
				(hide yes)
			)
		)
		(property "Description" "SMD Chip Resistor, 1 kohm, ± 1%, 63 mW, 0402 [1005 Metric], Thick Film, General Purpose"
			(at 90.17 110.49 0)
			(effects
				(font
					(size 1.27 1.27)
				)
				(hide yes)
			)
		)
		(property "MPN" "CR0402-FX-1001GLF"
			(at 110.49 90.17 0)
			(effects
				(font
					(size 1.27 1.27)
					(thickness 0.15)
				)
				(justify left bottom)
				(hide yes)
			)
		)
		(property "Manufacturer" "Bourns"
			(at 113.03 90.17 0)
			(effects
				(font
					(size 1.27 1.27)
					(thickness 0.15)
				)
				(justify left bottom)
				(hide yes)
			)
		)
		(property "License" "Apache-2.0"
			(at 115.57 90.17 0)
			(effects
				(font
					(size 1.27 1.27)
					(thickness 0.15)
				)
				(justify left bottom)
				(hide yes)
			)
		)
		(property "Author" "Antmicro"
			(at 118.11 90.17 0)
			(effects
				(font
					(size 1.27 1.27)
					(thickness 0.15)
				)
				(justify left bottom)
				(hide yes)
			)
		)
		(property "Val" "1k"
			(at 91.948 109.728 90)
			(effects
				(font
					(size 1.27 1.27)
					(thickness 0.15)
				)
				(justify right)
			)
		)
		(property "Tolerance" "1%"
			(at 100.33 90.17 0)
			(effects
				(font
					(size 1.27 1.27)
				)
				(justify left bottom)
				(hide yes)
			)
		)
		(pin "2"
		)
		(pin "1"
		)
		(instances
			(project "usb_debug_pd"
				(path ""
					(reference "R?")
					(unit 1)
				)
			)
			(project "jetson-agx-thor-baseboard"
				(path ""
					(reference "R114")
					(unit 1)
				)
			)
		)
	)
	(symbol
		(lib_id "antmicroResistors0402:R_0R_0402")
		(at 55.88 259.08 0)
		(unit 1)
		(exclude_from_sim no)
		(in_bom no)
		(on_board yes)
		(dnp yes)
		(property "Reference" "R388"
			(at 62.992 257.81 0)
			(effects
				(font
					(size 1.27 1.27)
					(thickness 0.15)
				)
			)
		)
		(property "Value" "R_0R_0402"
			(at 76.2 271.78 0)
			(effects
				(font
					(size 1.27 1.27)
					(thickness 0.15)
				)
				(justify left bottom)
				(hide yes)
			)
		)
		(property "Footprint" "antmicro-footprints:R_0402_1005Metric"
			(at 76.2 274.32 0)
			(effects
				(font
					(size 1.27 1.27)
					(thickness 0.15)
				)
				(justify left bottom)
				(hide yes)
			)
		)
		(property "Datasheet" "https://industrial.panasonic.com/cdbs/www-data/pdf/RDA0000/AOA0000C301.pdf"
			(at 76.2 276.86 0)
			(effects
				(font
					(size 1.27 1.27)
					(thickness 0.15)
				)
				(justify left bottom)
				(hide yes)
			)
		)
		(property "Description" "SMD Chip Resistor, Jumper, 0 ohm, 100 mW, 0402 [1005 Metric], Thick Film, General Purpose"
			(at 76.2 292.1 0)
			(effects
				(font
					(size 1.27 1.27)
				)
				(justify left bottom)
				(hide yes)
			)
		)
		(property "MPN" "ERJ2GE0R00X"
			(at 76.2 279.4 0)
			(effects
				(font
					(size 1.27 1.27)
					(thickness 0.15)
				)
				(justify left bottom)
				(hide yes)
			)
		)
		(property "Manufacturer" "Panasonic"
			(at 76.2 281.94 0)
			(effects
				(font
					(size 1.27 1.27)
					(thickness 0.15)
				)
				(justify left bottom)
				(hide yes)
			)
		)
		(property "License" "Apache-2.0"
			(at 76.2 284.48 0)
			(effects
				(font
					(size 1.27 1.27)
					(thickness 0.15)
				)
				(justify left bottom)
				(hide yes)
			)
		)
		(property "Author" "Antmicro"
			(at 76.2 287.02 0)
			(effects
				(font
					(size 1.27 1.27)
					(thickness 0.15)
				)
				(justify left bottom)
				(hide yes)
			)
		)
		(property "Val" "0R"
			(at 55.118 257.81 0)
			(effects
				(font
					(size 1.27 1.27)
					(thickness 0.15)
				)
			)
		)
		(property "Tolerance" "~"
			(at 76.2 269.24 0)
			(effects
				(font
					(size 1.27 1.27)
				)
				(justify left bottom)
				(hide yes)
			)
		)
		(property "Current" "1A"
			(at 76.2 289.56 0)
			(effects
				(font
					(size 1.27 1.27)
					(thickness 0.15)
				)
				(justify left bottom)
				(hide yes)
			)
		)
		(pin "2"
		)
		(pin "1"
		)
		(instances
			(project "jetson-agx-thor-baseboard"
				(path ""
					(reference "R388")
					(unit 1)
				)
			)
		)
	)
	(symbol
		(lib_id "antmicropower:GND")
		(at 283.21 44.45 0)
		(mirror y)
		(unit 1)
		(exclude_from_sim no)
		(in_bom yes)
		(on_board yes)
		(dnp no)
		(property "Reference" "#PWR0274"
			(at 283.21 50.8 0)
			(effects
				(font
					(size 1.27 1.27)
				)
				(justify left bottom)
				(hide yes)
			)
		)
		(property "Value" "GND"
			(at 283.21 48.26 0)
			(effects
				(font
					(size 1.27 1.27)
					(thickness 0.15)
				)
			)
		)
		(property "Footprint" ""
			(at 274.32 52.07 0)
			(effects
				(font
					(size 1.27 1.27)
					(thickness 0.15)
				)
				(justify left bottom)
				(hide yes)
			)
		)
		(property "Datasheet" ""
			(at 274.32 57.15 0)
			(effects
				(font
					(size 1.27 1.27)
					(thickness 0.15)
				)
				(justify left bottom)
				(hide yes)
			)
		)
		(property "Description" ""
			(at 283.21 44.45 0)
			(effects
				(font
					(size 1.27 1.27)
				)
				(hide yes)
			)
		)
		(property "Author" "Antmicro"
			(at 274.32 52.07 0)
			(effects
				(font
					(size 1.27 1.27)
					(thickness 0.15)
				)
				(justify left bottom)
				(hide yes)
			)
		)
		(property "License" "Apache-2.0"
			(at 274.32 54.61 0)
			(effects
				(font
					(size 1.27 1.27)
					(thickness 0.15)
				)
				(justify left bottom)
				(hide yes)
			)
		)
		(pin "1"
		)
		(instances
			(project "usb_debug_pd"
				(path ""
					(reference "#PWR?")
					(unit 1)
				)
			)
			(project "jetson-agx-thor-baseboard"
				(path ""
					(reference "#PWR0274")
					(unit 1)
				)
			)
		)
	)
	(symbol
		(lib_id "antmicroLEDIndicationDiscrete:LED_G_0603_LTST-C190GKT")
		(at 271.78 231.14 0)
		(mirror y)
		(unit 1)
		(exclude_from_sim no)
		(in_bom yes)
		(on_board yes)
		(dnp no)
		(property "Reference" "D18"
			(at 271.78 230.505 0)
			(effects
				(font
					(size 1.27 1.27)
				)
				(justify right bottom)
			)
		)
		(property "Value" "LED_G_0603_LTST-C190GKT"
			(at 248.92 238.76 0)
			(effects
				(font
					(size 1.27 1.27)
					(thickness 0.15)
				)
				(justify left bottom)
				(hide yes)
			)
		)
		(property "Footprint" "antmicro-footprints:LED_0603_1608Metric_G"
			(at 248.92 241.3 0)
			(effects
				(font
					(size 1.27 1.27)
					(thickness 0.15)
				)
				(justify left bottom)
				(hide yes)
			)
		)
		(property "Datasheet" "https://media.digikey.com/pdf/Data%20Sheets/Lite-On%20PDFs/LTST-C190GKT.pdf"
			(at 248.92 243.84 0)
			(effects
				(font
					(size 1.27 1.27)
					(thickness 0.15)
				)
				(justify left bottom)
				(hide yes)
			)
		)
		(property "Description" "LED, Green, SMD, 0603, 20 mA, 2.1 V, 569 nm"
			(at 271.78 231.14 0)
			(effects
				(font
					(size 1.27 1.27)
				)
				(hide yes)
			)
		)
		(property "MPN" "LTST-C190GKT"
			(at 248.92 246.38 0)
			(effects
				(font
					(size 1.27 1.27)
					(thickness 0.15)
				)
				(justify left bottom)
				(hide yes)
			)
		)
		(property "Manufacturer" "Lite-On"
			(at 248.92 248.92 0)
			(effects
				(font
					(size 1.27 1.27)
					(thickness 0.15)
				)
				(justify left bottom)
				(hide yes)
			)
		)
		(property "Author" "Antmicro"
			(at 248.92 251.46 0)
			(effects
				(font
					(size 1.27 1.27)
					(thickness 0.15)
				)
				(justify left bottom)
				(hide yes)
			)
		)
		(property "License" "Apache-2.0"
			(at 248.92 254 0)
			(effects
				(font
					(size 1.27 1.27)
					(thickness 0.15)
				)
				(justify left bottom)
				(hide yes)
			)
		)
		(property "Color" "Green"
			(at 266.065 227.965 0)
			(effects
				(font
					(size 1.27 1.27)
				)
				(justify right bottom)
			)
		)
		(pin "1"
		)
		(pin "2"
		)
		(instances
			(project "usb_debug_pd"
				(path ""
					(reference "D?")
					(unit 1)
				)
			)
			(project "jetson-agx-thor-baseboard"
				(path ""
					(reference "D18")
					(unit 1)
				)
			)
		)
	)
	(symbol
		(lib_id "antmicroTransistorsFETsMOSFETsSingle:DMG1012T-7")
		(at 104.14 137.16 0)
		(mirror y)
		(unit 1)
		(exclude_from_sim no)
		(in_bom yes)
		(on_board yes)
		(dnp no)
		(property "Reference" "Q12"
			(at 123.19 131.064 0)
			(effects
				(font
					(size 1.27 1.27)
					(thickness 0.15)
				)
				(justify left)
			)
		)
		(property "Value" "DMG1012T-7"
			(at 81.28 146.05 0)
			(effects
				(font
					(size 1.27 1.27)
					(thickness 0.15)
				)
				(justify left bottom)
				(hide yes)
			)
		)
		(property "Footprint" "antmicro-footprints:SOT-523"
			(at 81.28 148.59 0)
			(effects
				(font
					(size 1.27 1.27)
					(thickness 0.15)
				)
				(justify left bottom)
				(hide yes)
			)
		)
		(property "Datasheet" "https://www.diodes.com/assets/Datasheets/ds31783.pdf"
			(at 81.28 151.13 0)
			(effects
				(font
					(size 1.27 1.27)
					(thickness 0.15)
				)
				(justify left bottom)
				(hide yes)
			)
		)
		(property "Description" "Power MOSFET, N Channel, 20 V, 630 mA, 0.3 ohm, SOT-523, Surface Mount"
			(at 81.28 163.83 0)
			(effects
				(font
					(size 1.27 1.27)
				)
				(justify left bottom)
				(hide yes)
			)
		)
		(property "MPN" "DMG1012T-7"
			(at 123.19 133.604 0)
			(effects
				(font
					(size 1.27 1.27)
					(thickness 0.15)
				)
				(justify left)
			)
		)
		(property "Manufacturer" "Diodes Incorporated"
			(at 81.28 156.21 0)
			(effects
				(font
					(size 1.27 1.27)
					(thickness 0.15)
				)
				(justify left bottom)
				(hide yes)
			)
		)
		(property "Author" "Antmicro"
			(at 81.28 158.75 0)
			(effects
				(font
					(size 1.27 1.27)
					(thickness 0.15)
				)
				(justify left bottom)
				(hide yes)
			)
		)
		(property "License" "Apache-2.0"
			(at 81.28 161.29 0)
			(effects
				(font
					(size 1.27 1.27)
					(thickness 0.15)
				)
				(justify left bottom)
				(hide yes)
			)
		)
		(pin "2"
		)
		(pin "3"
		)
		(pin "1"
		)
		(instances
			(project "usb_debug_pd"
				(path ""
					(reference "Q?")
					(unit 1)
				)
			)
			(project "jetson-agx-thor-baseboard"
				(path ""
					(reference "Q12")
					(unit 1)
				)
			)
		)
	)
	(symbol
		(lib_id "antmicroResistors0402:R_200R_0402")
		(at 113.03 95.25 90)
		(unit 1)
		(exclude_from_sim no)
		(in_bom yes)
		(on_board yes)
		(dnp no)
		(fields_autoplaced yes)
		(property "Reference" "R119"
			(at 110.49 91.4399 90)
			(effects
				(font
					(size 1.27 1.27)
				)
				(justify left)
			)
		)
		(property "Value" "R_200R_0402"
			(at 125.73 74.93 0)
			(effects
				(font
					(size 1.27 1.27)
					(thickness 0.15)
				)
				(justify left bottom)
				(hide yes)
			)
		)
		(property "Footprint" "antmicro-footprints:R_0402_1005Metric"
			(at 128.27 74.93 0)
			(effects
				(font
					(size 1.27 1.27)
					(thickness 0.15)
				)
				(justify left bottom)
				(hide yes)
			)
		)
		(property "Datasheet" "https://www.bourns.com/docs/product-datasheets/cr.pdf"
			(at 130.81 74.93 0)
			(effects
				(font
					(size 1.27 1.27)
					(thickness 0.15)
				)
				(justify left bottom)
				(hide yes)
			)
		)
		(property "Description" "SMD Chip Resistor, 200 ohm, ± 1%, 62.5 mW, 0402 [1005 Metric], Thick Film, General Purpose"
			(at 113.03 95.25 0)
			(effects
				(font
					(size 1.27 1.27)
				)
				(hide yes)
			)
		)
		(property "Manufacturer" "Bourns"
			(at 135.89 74.93 0)
			(effects
				(font
					(size 1.27 1.27)
					(thickness 0.15)
				)
				(justify left bottom)
				(hide yes)
			)
		)
		(property "MPN" "CR0402-FX-2000GLF"
			(at 133.35 74.93 0)
			(effects
				(font
					(size 1.27 1.27)
					(thickness 0.15)
				)
				(justify left bottom)
				(hide yes)
			)
		)
		(property "Val" "200R"
			(at 110.49 93.98 90)
			(effects
				(font
					(size 1.27 1.27)
					(thickness 0.15)
				)
				(justify left)
			)
		)
		(property "License" "Apache-2.0"
			(at 138.43 74.93 0)
			(effects
				(font
					(size 1.27 1.27)
					(thickness 0.15)
				)
				(justify left bottom)
				(hide yes)
			)
		)
		(property "Author" "Antmicro"
			(at 140.97 74.93 0)
			(effects
				(font
					(size 1.27 1.27)
					(thickness 0.15)
				)
				(justify left bottom)
				(hide yes)
			)
		)
		(property "Tolerance" "1%"
			(at 123.19 74.93 0)
			(effects
				(font
					(size 1.27 1.27)
				)
				(justify left bottom)
				(hide yes)
			)
		)
		(pin "1"
		)
		(pin "2"
		)
		(instances
			(project "usb_debug_pd"
				(path ""
					(reference "R?")
					(unit 1)
				)
			)
			(project "jetson-agx-thor-baseboard"
				(path ""
					(reference "R119")
					(unit 1)
				)
			)
		)
	)
	(symbol
		(lib_id "antmicropower:PWR_FLAG")
		(at 39.37 201.93 0)
		(unit 1)
		(exclude_from_sim no)
		(in_bom yes)
		(on_board yes)
		(dnp no)
		(property "Reference" "#FLG09"
			(at 39.37 200.025 0)
			(effects
				(font
					(size 1.27 1.27)
				)
				(hide yes)
			)
		)
		(property "Value" "PWR_FLAG"
			(at 39.37 198.12 0)
			(effects
				(font
					(size 1.27 1.27)
				)
			)
		)
		(property "Footprint" ""
			(at 39.37 201.93 0)
			(effects
				(font
					(size 1.27 1.27)
				)
				(hide yes)
			)
		)
		(property "Datasheet" ""
			(at 39.37 201.93 0)
			(effects
				(font
					(size 1.27 1.27)
				)
				(hide yes)
			)
		)
		(property "Description" ""
			(at 39.37 201.93 0)
			(effects
				(font
					(size 1.27 1.27)
				)
				(hide yes)
			)
		)
		(pin "1"
		)
		(instances
			(project "usb_debug_pd"
				(path ""
					(reference "#FLG?")
					(unit 1)
				)
			)
			(project "jetson-agx-thor-baseboard"
				(path ""
					(reference "#FLG09")
					(unit 1)
				)
			)
		)
	)
	(symbol
		(lib_id "antmicroCapacitors0402:C_10u_0402")
		(at 138.43 196.85 90)
		(unit 1)
		(exclude_from_sim no)
		(in_bom yes)
		(on_board yes)
		(dnp no)
		(property "Reference" "C118"
			(at 139.065 192.405 90)
			(effects
				(font
					(size 1.27 1.27)
					(thickness 0.15)
				)
				(justify right)
			)
		)
		(property "Value" "C_10u_0402"
			(at 148.59 176.53 0)
			(effects
				(font
					(size 1.27 1.27)
					(thickness 0.15)
				)
				(justify left bottom)
				(hide yes)
			)
		)
		(property "Footprint" "antmicro-footprints:C_0402_1005Metric"
			(at 151.13 176.53 0)
			(effects
				(font
					(size 1.27 1.27)
					(thickness 0.15)
				)
				(justify left bottom)
				(hide yes)
			)
		)
		(property "Datasheet" "https://www.yageo.com/en/Chart/Download/pdf/CC0402MRX5R5BB106"
			(at 153.67 176.53 0)
			(effects
				(font
					(size 1.27 1.27)
					(thickness 0.15)
				)
				(justify left bottom)
				(hide yes)
			)
		)
		(property "Description" "SMD Multilayer Ceramic Capacitor, 10 µF, 6.3 V, 0402 [1005 Metric], ± 20%, X5R, CC Series"
			(at 138.43 196.85 0)
			(effects
				(font
					(size 1.27 1.27)
				)
				(hide yes)
			)
		)
		(property "MPN" "CC0402MRX5R5BB106"
			(at 156.21 176.53 0)
			(effects
				(font
					(size 1.27 1.27)
					(thickness 0.15)
				)
				(justify left bottom)
				(hide yes)
			)
		)
		(property "Manufacturer" "YAGEO"
			(at 158.75 176.53 0)
			(effects
				(font
					(size 1.27 1.27)
					(thickness 0.15)
				)
				(justify left bottom)
				(hide yes)
			)
		)
		(property "License" "Apache-2.0"
			(at 161.29 176.53 0)
			(effects
				(font
					(size 1.27 1.27)
					(thickness 0.15)
				)
				(justify left bottom)
				(hide yes)
			)
		)
		(property "Author" "Antmicro"
			(at 163.83 176.53 0)
			(effects
				(font
					(size 1.27 1.27)
					(thickness 0.15)
				)
				(justify left bottom)
				(hide yes)
			)
		)
		(property "Val" "10u"
			(at 139.065 196.215 90)
			(effects
				(font
					(size 1.27 1.27)
					(thickness 0.15)
				)
				(justify right)
			)
		)
		(property "Voltage" ""
			(at 166.37 176.53 0)
			(effects
				(font
					(size 1.27 1.27)
				)
				(justify left bottom)
				(hide yes)
			)
		)
		(property "Dielectric" ""
			(at 168.91 176.53 0)
			(effects
				(font
					(size 1.27 1.27)
				)
				(justify left bottom)
				(hide yes)
			)
		)
		(pin "1"
		)
		(pin "2"
		)
		(instances
			(project "usb_debug_pd"
				(path ""
					(reference "C?")
					(unit 1)
				)
			)
			(project "jetson-agx-thor-baseboard"
				(path ""
					(reference "C118")
					(unit 1)
				)
			)
		)
	)
	(symbol
		(lib_id "antmicroTestPoints:TP_0.75mm_SMD")
		(at 233.68 207.01 0)
		(unit 1)
		(exclude_from_sim no)
		(in_bom no)
		(on_board yes)
		(dnp no)
		(property "Reference" "TP10"
			(at 237.49 207.645 0)
			(effects
				(font
					(size 1.27 1.27)
				)
				(justify left bottom)
			)
		)
		(property "Value" "TP_0.75mm_SMD"
			(at 243.84 210.82 0)
			(effects
				(font
					(size 1.27 1.27)
					(thickness 0.15)
				)
				(justify left bottom)
				(hide yes)
			)
		)
		(property "Footprint" "antmicro-footprints:TP_SMD_0.75mm"
			(at 243.84 213.36 0)
			(effects
				(font
					(size 1.27 1.27)
					(thickness 0.15)
				)
				(justify left bottom)
				(hide yes)
			)
		)
		(property "Datasheet" ""
			(at 251.46 219.71 0)
			(effects
				(font
					(size 1.27 1.27)
					(thickness 0.15)
				)
				(justify left bottom)
				(hide yes)
			)
		)
		(property "Description" "SMT test point"
			(at 233.68 207.01 0)
			(effects
				(font
					(size 1.27 1.27)
				)
				(hide yes)
			)
		)
		(property "MPN" ""
			(at 244.475 218.44 0)
			(effects
				(font
					(size 1.27 1.27)
					(thickness 0.15)
				)
				(justify left bottom)
				(hide yes)
			)
		)
		(property "Manufacturer" ""
			(at 244.475 213.36 0)
			(effects
				(font
					(size 1.27 1.27)
					(thickness 0.15)
				)
				(justify left bottom)
				(hide yes)
			)
		)
		(property "Author" "Antmicro"
			(at 243.84 215.9 0)
			(effects
				(font
					(size 1.27 1.27)
					(thickness 0.15)
				)
				(justify left bottom)
				(hide yes)
			)
		)
		(property "License" "Apache-2.0"
			(at 243.84 218.44 0)
			(effects
				(font
					(size 1.27 1.27)
					(thickness 0.15)
				)
				(justify left bottom)
				(hide yes)
			)
		)
		(pin "1"
		)
		(instances
			(project "usb_debug_pd"
				(path ""
					(reference "TP?")
					(unit 1)
				)
			)
			(project "jetson-agx-thor-baseboard"
				(path ""
					(reference "TP10")
					(unit 1)
				)
			)
		)
	)
	(symbol
		(lib_id "antmicroTestPoints:TP_0.75mm_SMD")
		(at 260.35 200.66 0)
		(unit 1)
		(exclude_from_sim no)
		(in_bom no)
		(on_board yes)
		(dnp no)
		(property "Reference" "TP16"
			(at 264.16 201.295 0)
			(effects
				(font
					(size 1.27 1.27)
				)
				(justify left bottom)
			)
		)
		(property "Value" "TP_0.75mm_SMD"
			(at 270.51 204.47 0)
			(effects
				(font
					(size 1.27 1.27)
					(thickness 0.15)
				)
				(justify left bottom)
				(hide yes)
			)
		)
		(property "Footprint" "antmicro-footprints:TP_SMD_0.75mm"
			(at 270.51 207.01 0)
			(effects
				(font
					(size 1.27 1.27)
					(thickness 0.15)
				)
				(justify left bottom)
				(hide yes)
			)
		)
		(property "Datasheet" ""
			(at 278.13 213.36 0)
			(effects
				(font
					(size 1.27 1.27)
					(thickness 0.15)
				)
				(justify left bottom)
				(hide yes)
			)
		)
		(property "Description" "SMT test point"
			(at 260.35 200.66 0)
			(effects
				(font
					(size 1.27 1.27)
				)
				(hide yes)
			)
		)
		(property "MPN" ""
			(at 271.145 212.09 0)
			(effects
				(font
					(size 1.27 1.27)
					(thickness 0.15)
				)
				(justify left bottom)
				(hide yes)
			)
		)
		(property "Manufacturer" ""
			(at 271.145 207.01 0)
			(effects
				(font
					(size 1.27 1.27)
					(thickness 0.15)
				)
				(justify left bottom)
				(hide yes)
			)
		)
		(property "Author" "Antmicro"
			(at 270.51 209.55 0)
			(effects
				(font
					(size 1.27 1.27)
					(thickness 0.15)
				)
				(justify left bottom)
				(hide yes)
			)
		)
		(property "License" "Apache-2.0"
			(at 270.51 212.09 0)
			(effects
				(font
					(size 1.27 1.27)
					(thickness 0.15)
				)
				(justify left bottom)
				(hide yes)
			)
		)
		(pin "1"
		)
		(instances
			(project "usb_debug_pd"
				(path ""
					(reference "TP?")
					(unit 1)
				)
			)
			(project "jetson-agx-thor-baseboard"
				(path ""
					(reference "TP16")
					(unit 1)
				)
			)
		)
	)
	(symbol
		(lib_id "antmicropower:GND")
		(at 327.66 39.37 0)
		(mirror y)
		(unit 1)
		(exclude_from_sim no)
		(in_bom yes)
		(on_board yes)
		(dnp no)
		(property "Reference" "#PWR0272"
			(at 327.66 45.72 0)
			(effects
				(font
					(size 1.27 1.27)
				)
				(justify left bottom)
				(hide yes)
			)
		)
		(property "Value" "GND"
			(at 327.66 43.18 0)
			(effects
				(font
					(size 1.27 1.27)
					(thickness 0.15)
				)
			)
		)
		(property "Footprint" ""
			(at 318.77 46.99 0)
			(effects
				(font
					(size 1.27 1.27)
					(thickness 0.15)
				)
				(justify left bottom)
				(hide yes)
			)
		)
		(property "Datasheet" ""
			(at 318.77 52.07 0)
			(effects
				(font
					(size 1.27 1.27)
					(thickness 0.15)
				)
				(justify left bottom)
				(hide yes)
			)
		)
		(property "Description" ""
			(at 327.66 39.37 0)
			(effects
				(font
					(size 1.27 1.27)
				)
				(hide yes)
			)
		)
		(property "Author" "Antmicro"
			(at 318.77 46.99 0)
			(effects
				(font
					(size 1.27 1.27)
					(thickness 0.15)
				)
				(justify left bottom)
				(hide yes)
			)
		)
		(property "License" "Apache-2.0"
			(at 318.77 49.53 0)
			(effects
				(font
					(size 1.27 1.27)
					(thickness 0.15)
				)
				(justify left bottom)
				(hide yes)
			)
		)
		(pin "1"
		)
		(instances
			(project "usb_debug_pd"
				(path ""
					(reference "#PWR?")
					(unit 1)
				)
			)
			(project "jetson-agx-thor-baseboard"
				(path ""
					(reference "#PWR0272")
					(unit 1)
				)
			)
		)
	)
	(symbol
		(lib_id "antmicroResistors0402:R_0R_0402")
		(at 241.3 203.2 180)
		(unit 1)
		(exclude_from_sim no)
		(in_bom yes)
		(on_board yes)
		(dnp no)
		(property "Reference" "R106"
			(at 241.3 202.565 0)
			(effects
				(font
					(size 1.27 1.27)
				)
				(justify right top)
			)
		)
		(property "Value" "R_0R_0402"
			(at 220.98 190.5 0)
			(effects
				(font
					(size 1.27 1.27)
					(thickness 0.15)
				)
				(justify left bottom)
				(hide yes)
			)
		)
		(property "Footprint" "antmicro-footprints:R_0402_1005Metric"
			(at 220.98 187.96 0)
			(effects
				(font
					(size 1.27 1.27)
					(thickness 0.15)
				)
				(justify left bottom)
				(hide yes)
			)
		)
		(property "Datasheet" "https://industrial.panasonic.com/cdbs/www-data/pdf/RDA0000/AOA0000C301.pdf"
			(at 220.98 185.42 0)
			(effects
				(font
					(size 1.27 1.27)
					(thickness 0.15)
				)
				(justify left bottom)
				(hide yes)
			)
		)
		(property "Description" "SMD Chip Resistor, Jumper, 0 ohm, 100 mW, 0402 [1005 Metric], Thick Film, General Purpose"
			(at 241.3 203.2 0)
			(effects
				(font
					(size 1.27 1.27)
				)
				(hide yes)
			)
		)
		(property "Manufacturer" "Panasonic"
			(at 220.98 180.34 0)
			(effects
				(font
					(size 1.27 1.27)
					(thickness 0.15)
				)
				(justify left bottom)
				(hide yes)
			)
		)
		(property "MPN" "ERJ2GE0R00X"
			(at 220.98 182.88 0)
			(effects
				(font
					(size 1.27 1.27)
					(thickness 0.15)
				)
				(justify left bottom)
				(hide yes)
			)
		)
		(property "Val" "0R"
			(at 233.68 202.565 0)
			(effects
				(font
					(size 1.27 1.27)
					(thickness 0.15)
				)
				(justify right top)
			)
		)
		(property "License" "Apache-2.0"
			(at 220.98 177.8 0)
			(effects
				(font
					(size 1.27 1.27)
					(thickness 0.15)
				)
				(justify left bottom)
				(hide yes)
			)
		)
		(property "Author" "Antmicro"
			(at 220.98 175.26 0)
			(effects
				(font
					(size 1.27 1.27)
					(thickness 0.15)
				)
				(justify left bottom)
				(hide yes)
			)
		)
		(property "Tolerance" "~"
			(at 220.98 193.04 0)
			(effects
				(font
					(size 1.27 1.27)
				)
				(justify left bottom)
				(hide yes)
			)
		)
		(property "Current" "1A"
			(at 220.98 172.72 0)
			(effects
				(font
					(size 1.27 1.27)
					(thickness 0.15)
				)
				(justify left bottom)
				(hide yes)
			)
		)
		(pin "1"
		)
		(pin "2"
		)
		(instances
			(project "usb_debug_pd"
				(path ""
					(reference "R?")
					(unit 1)
				)
			)
			(project "jetson-agx-thor-baseboard"
				(path ""
					(reference "R106")
					(unit 1)
				)
			)
		)
	)
	(symbol
		(lib_id "antmicropower:GND")
		(at 199.39 124.46 0)
		(unit 1)
		(exclude_from_sim no)
		(in_bom yes)
		(on_board yes)
		(dnp no)
		(property "Reference" "#PWR0258"
			(at 199.39 130.81 0)
			(effects
				(font
					(size 1.27 1.27)
				)
				(justify left bottom)
				(hide yes)
			)
		)
		(property "Value" "GND"
			(at 199.39 128.27 0)
			(effects
				(font
					(size 1.27 1.27)
					(thickness 0.15)
				)
			)
		)
		(property "Footprint" ""
			(at 208.28 132.08 0)
			(effects
				(font
					(size 1.27 1.27)
					(thickness 0.15)
				)
				(justify left bottom)
				(hide yes)
			)
		)
		(property "Datasheet" ""
			(at 208.28 137.16 0)
			(effects
				(font
					(size 1.27 1.27)
					(thickness 0.15)
				)
				(justify left bottom)
				(hide yes)
			)
		)
		(property "Description" ""
			(at 199.39 124.46 0)
			(effects
				(font
					(size 1.27 1.27)
				)
				(hide yes)
			)
		)
		(property "Author" "Antmicro"
			(at 208.28 132.08 0)
			(effects
				(font
					(size 1.27 1.27)
					(thickness 0.15)
				)
				(justify left bottom)
				(hide yes)
			)
		)
		(property "License" "Apache-2.0"
			(at 208.28 134.62 0)
			(effects
				(font
					(size 1.27 1.27)
					(thickness 0.15)
				)
				(justify left bottom)
				(hide yes)
			)
		)
		(pin "1"
		)
		(instances
			(project "usb_debug_pd"
				(path ""
					(reference "#PWR?")
					(unit 1)
				)
			)
			(project "jetson-agx-thor-baseboard"
				(path ""
					(reference "#PWR0258")
					(unit 1)
				)
			)
		)
	)
	(symbol
		(lib_id "antmicroCapacitors0402:C_100n_0402")
		(at 146.05 191.77 270)
		(unit 1)
		(exclude_from_sim no)
		(in_bom yes)
		(on_board yes)
		(dnp no)
		(property "Reference" "C119"
			(at 146.685 192.405 90)
			(effects
				(font
					(size 1.27 1.27)
				)
				(justify left)
			)
		)
		(property "Value" "C_100n_0402"
			(at 135.89 212.09 0)
			(effects
				(font
					(size 1.27 1.27)
					(thickness 0.15)
				)
				(justify left bottom)
				(hide yes)
			)
		)
		(property "Footprint" "antmicro-footprints:C_0402_1005Metric"
			(at 133.35 212.09 0)
			(effects
				(font
					(size 1.27 1.27)
					(thickness 0.15)
				)
				(justify left bottom)
				(hide yes)
			)
		)
		(property "Datasheet" "https://www.murata.com/products/productdetail?partno=GRM155R61H104KE14%23"
			(at 130.81 212.09 0)
			(effects
				(font
					(size 1.27 1.27)
					(thickness 0.15)
				)
				(justify left bottom)
				(hide yes)
			)
		)
		(property "Description" "SMD Multilayer Ceramic Capacitor, 0.1 µF, 50 V, 0402 [1005 Metric], ± 10%, X5R, GRM Series"
			(at 146.05 191.77 0)
			(effects
				(font
					(size 1.27 1.27)
				)
				(hide yes)
			)
		)
		(property "Manufacturer" "Murata"
			(at 125.73 212.09 0)
			(effects
				(font
					(size 1.27 1.27)
					(thickness 0.15)
				)
				(justify left bottom)
				(hide yes)
			)
		)
		(property "MPN" "GRM155R61H104KE14D"
			(at 128.27 212.09 0)
			(effects
				(font
					(size 1.27 1.27)
					(thickness 0.15)
				)
				(justify left bottom)
				(hide yes)
			)
		)
		(property "Val" "100n"
			(at 146.685 196.215 90)
			(effects
				(font
					(size 1.27 1.27)
					(thickness 0.15)
				)
				(justify left)
			)
		)
		(property "License" "Apache-2.0"
			(at 123.19 212.09 0)
			(effects
				(font
					(size 1.27 1.27)
					(thickness 0.15)
				)
				(justify left bottom)
				(hide yes)
			)
		)
		(property "Author" "Antmicro"
			(at 120.65 212.09 0)
			(effects
				(font
					(size 1.27 1.27)
					(thickness 0.15)
				)
				(justify left bottom)
				(hide yes)
			)
		)
		(property "Voltage" "50V"
			(at 118.11 212.09 0)
			(effects
				(font
					(size 1.27 1.27)
				)
				(justify left bottom)
				(hide yes)
			)
		)
		(property "Dielectric" "X5R"
			(at 115.57 212.09 0)
			(effects
				(font
					(size 1.27 1.27)
				)
				(justify left bottom)
				(hide yes)
			)
		)
		(pin "1"
		)
		(pin "2"
		)
		(instances
			(project "usb_debug_pd"
				(path ""
					(reference "C?")
					(unit 1)
				)
			)
			(project "jetson-agx-thor-baseboard"
				(path ""
					(reference "C119")
					(unit 1)
				)
			)
		)
	)
	(symbol
		(lib_id "antmicroCapacitors0402:C_10u_0402")
		(at 153.67 71.12 270)
		(mirror x)
		(unit 1)
		(exclude_from_sim no)
		(in_bom yes)
		(on_board yes)
		(dnp no)
		(fields_autoplaced yes)
		(property "Reference" "C135"
			(at 151.13 67.3036 90)
			(effects
				(font
					(size 1.27 1.27)
					(thickness 0.15)
				)
				(justify right)
			)
		)
		(property "Value" "C_10u_0402"
			(at 143.51 50.8 0)
			(effects
				(font
					(size 1.27 1.27)
					(thickness 0.15)
				)
				(justify left bottom)
				(hide yes)
			)
		)
		(property "Footprint" "antmicro-footprints:C_0402_1005Metric"
			(at 140.97 50.8 0)
			(effects
				(font
					(size 1.27 1.27)
					(thickness 0.15)
				)
				(justify left bottom)
				(hide yes)
			)
		)
		(property "Datasheet" "https://www.yageo.com/en/Chart/Download/pdf/CC0402MRX5R5BB106"
			(at 138.43 50.8 0)
			(effects
				(font
					(size 1.27 1.27)
					(thickness 0.15)
				)
				(justify left bottom)
				(hide yes)
			)
		)
		(property "Description" "SMD Multilayer Ceramic Capacitor, 10 µF, 6.3 V, 0402 [1005 Metric], ± 20%, X5R, CC Series"
			(at 153.67 71.12 0)
			(effects
				(font
					(size 1.27 1.27)
				)
				(hide yes)
			)
		)
		(property "MPN" "CC0402MRX5R5BB106"
			(at 135.89 50.8 0)
			(effects
				(font
					(size 1.27 1.27)
					(thickness 0.15)
				)
				(justify left bottom)
				(hide yes)
			)
		)
		(property "Manufacturer" "YAGEO"
			(at 133.35 50.8 0)
			(effects
				(font
					(size 1.27 1.27)
					(thickness 0.15)
				)
				(justify left bottom)
				(hide yes)
			)
		)
		(property "License" "Apache-2.0"
			(at 130.81 50.8 0)
			(effects
				(font
					(size 1.27 1.27)
					(thickness 0.15)
				)
				(justify left bottom)
				(hide yes)
			)
		)
		(property "Author" "Antmicro"
			(at 128.27 50.8 0)
			(effects
				(font
					(size 1.27 1.27)
					(thickness 0.15)
				)
				(justify left bottom)
				(hide yes)
			)
		)
		(property "Val" "10u"
			(at 151.13 69.8436 90)
			(effects
				(font
					(size 1.27 1.27)
					(thickness 0.15)
				)
				(justify right)
			)
		)
		(property "Voltage" ""
			(at 125.73 50.8 0)
			(effects
				(font
					(size 1.27 1.27)
				)
				(justify left bottom)
				(hide yes)
			)
		)
		(property "Dielectric" ""
			(at 123.19 50.8 0)
			(effects
				(font
					(size 1.27 1.27)
				)
				(justify left bottom)
				(hide yes)
			)
		)
		(pin "1"
		)
		(pin "2"
		)
		(instances
			(project "usb_debug_pd"
				(path ""
					(reference "C?")
					(unit 1)
				)
			)
			(project "jetson-agx-thor-baseboard"
				(path ""
					(reference "C135")
					(unit 1)
				)
			)
		)
	)
	(symbol
		(lib_id "antmicropower:GND")
		(at 359.41 45.72 0)
		(mirror y)
		(unit 1)
		(exclude_from_sim no)
		(in_bom yes)
		(on_board yes)
		(dnp no)
		(property "Reference" "#PWR0283"
			(at 359.41 52.07 0)
			(effects
				(font
					(size 1.27 1.27)
				)
				(justify left bottom)
				(hide yes)
			)
		)
		(property "Value" "GND"
			(at 359.41 49.53 0)
			(effects
				(font
					(size 1.27 1.27)
					(thickness 0.15)
				)
			)
		)
		(property "Footprint" ""
			(at 350.52 53.34 0)
			(effects
				(font
					(size 1.27 1.27)
					(thickness 0.15)
				)
				(justify left bottom)
				(hide yes)
			)
		)
		(property "Datasheet" ""
			(at 350.52 58.42 0)
			(effects
				(font
					(size 1.27 1.27)
					(thickness 0.15)
				)
				(justify left bottom)
				(hide yes)
			)
		)
		(property "Description" ""
			(at 359.41 45.72 0)
			(effects
				(font
					(size 1.27 1.27)
				)
				(hide yes)
			)
		)
		(property "Author" "Antmicro"
			(at 350.52 53.34 0)
			(effects
				(font
					(size 1.27 1.27)
					(thickness 0.15)
				)
				(justify left bottom)
				(hide yes)
			)
		)
		(property "License" "Apache-2.0"
			(at 350.52 55.88 0)
			(effects
				(font
					(size 1.27 1.27)
					(thickness 0.15)
				)
				(justify left bottom)
				(hide yes)
			)
		)
		(pin "1"
		)
		(instances
			(project "usb_debug_pd"
				(path ""
					(reference "#PWR?")
					(unit 1)
				)
			)
			(project "jetson-agx-thor-baseboard"
				(path ""
					(reference "#PWR0283")
					(unit 1)
				)
			)
		)
	)
	(symbol
		(lib_id "antmicroLEDIndicationDiscrete:LED_G_0603_LTST-C190GKT")
		(at 359.41 44.45 90)
		(unit 1)
		(exclude_from_sim no)
		(in_bom yes)
		(on_board yes)
		(dnp no)
		(property "Reference" "D24"
			(at 361.315 40.64 90)
			(effects
				(font
					(size 1.27 1.27)
				)
				(justify right)
			)
		)
		(property "Value" "LED_G_0603_LTST-C190GKT"
			(at 367.03 21.59 0)
			(effects
				(font
					(size 1.27 1.27)
					(thickness 0.15)
				)
				(justify left bottom)
				(hide yes)
			)
		)
		(property "Footprint" "antmicro-footprints:LED_0603_1608Metric_G"
			(at 369.57 21.59 0)
			(effects
				(font
					(size 1.27 1.27)
					(thickness 0.15)
				)
				(justify left bottom)
				(hide yes)
			)
		)
		(property "Datasheet" "https://media.digikey.com/pdf/Data%20Sheets/Lite-On%20PDFs/LTST-C190GKT.pdf"
			(at 372.11 21.59 0)
			(effects
				(font
					(size 1.27 1.27)
					(thickness 0.15)
				)
				(justify left bottom)
				(hide yes)
			)
		)
		(property "Description" "LED, Green, SMD, 0603, 20 mA, 2.1 V, 569 nm"
			(at 359.41 44.45 0)
			(effects
				(font
					(size 1.27 1.27)
				)
				(hide yes)
			)
		)
		(property "MPN" "LTST-C190GKT"
			(at 374.65 21.59 0)
			(effects
				(font
					(size 1.27 1.27)
					(thickness 0.15)
				)
				(justify left bottom)
				(hide yes)
			)
		)
		(property "Manufacturer" "Lite-On"
			(at 377.19 21.59 0)
			(effects
				(font
					(size 1.27 1.27)
					(thickness 0.15)
				)
				(justify left bottom)
				(hide yes)
			)
		)
		(property "Author" "Antmicro"
			(at 379.73 21.59 0)
			(effects
				(font
					(size 1.27 1.27)
					(thickness 0.15)
				)
				(justify left bottom)
				(hide yes)
			)
		)
		(property "License" "Apache-2.0"
			(at 382.27 21.59 0)
			(effects
				(font
					(size 1.27 1.27)
					(thickness 0.15)
				)
				(justify left bottom)
				(hide yes)
			)
		)
		(property "Color" "Green"
			(at 359.918 43.942 90)
			(effects
				(font
					(size 1.27 1.27)
				)
				(justify right)
			)
		)
		(pin "1"
		)
		(pin "2"
		)
		(instances
			(project "usb_debug_pd"
				(path ""
					(reference "D?")
					(unit 1)
				)
			)
			(project "jetson-agx-thor-baseboard"
				(path ""
					(reference "D24")
					(unit 1)
				)
			)
		)
	)
	(symbol
		(lib_id "antmicroCapacitors0402:C_100n_0402")
		(at 337.82 33.02 270)
		(unit 1)
		(exclude_from_sim no)
		(in_bom yes)
		(on_board yes)
		(dnp no)
		(property "Reference" "C152"
			(at 339.725 34.29 90)
			(effects
				(font
					(size 1.27 1.27)
				)
				(justify left)
			)
		)
		(property "Value" "C_100n_0402"
			(at 327.66 53.34 0)
			(effects
				(font
					(size 1.27 1.27)
					(thickness 0.15)
				)
				(justify left bottom)
				(hide yes)
			)
		)
		(property "Footprint" "antmicro-footprints:C_0402_1005Metric"
			(at 325.12 53.34 0)
			(effects
				(font
					(size 1.27 1.27)
					(thickness 0.15)
				)
				(justify left bottom)
				(hide yes)
			)
		)
		(property "Datasheet" "https://www.murata.com/products/productdetail?partno=GRM155R61H104KE14%23"
			(at 322.58 53.34 0)
			(effects
				(font
					(size 1.27 1.27)
					(thickness 0.15)
				)
				(justify left bottom)
				(hide yes)
			)
		)
		(property "Description" "SMD Multilayer Ceramic Capacitor, 0.1 µF, 50 V, 0402 [1005 Metric], ± 10%, X5R, GRM Series"
			(at 337.82 33.02 0)
			(effects
				(font
					(size 1.27 1.27)
				)
				(hide yes)
			)
		)
		(property "MPN" "GRM155R61H104KE14D"
			(at 320.04 53.34 0)
			(effects
				(font
					(size 1.27 1.27)
					(thickness 0.15)
				)
				(justify left bottom)
				(hide yes)
			)
		)
		(property "Manufacturer" "Murata"
			(at 317.5 53.34 0)
			(effects
				(font
					(size 1.27 1.27)
					(thickness 0.15)
				)
				(justify left bottom)
				(hide yes)
			)
		)
		(property "Val" "100n"
			(at 339.725 36.83 90)
			(effects
				(font
					(size 1.27 1.27)
					(thickness 0.15)
				)
				(justify left)
			)
		)
		(property "License" "Apache-2.0"
			(at 314.96 53.34 0)
			(effects
				(font
					(size 1.27 1.27)
					(thickness 0.15)
				)
				(justify left bottom)
				(hide yes)
			)
		)
		(property "Author" "Antmicro"
			(at 312.42 53.34 0)
			(effects
				(font
					(size 1.27 1.27)
					(thickness 0.15)
				)
				(justify left bottom)
				(hide yes)
			)
		)
		(property "Voltage" "50V"
			(at 309.88 53.34 0)
			(effects
				(font
					(size 1.27 1.27)
				)
				(justify left bottom)
				(hide yes)
			)
		)
		(property "Dielectric" "X5R"
			(at 307.34 53.34 0)
			(effects
				(font
					(size 1.27 1.27)
				)
				(justify left bottom)
				(hide yes)
			)
		)
		(pin "1"
		)
		(pin "2"
		)
		(instances
			(project "usb_debug_pd"
				(path ""
					(reference "C?")
					(unit 1)
				)
			)
			(project "jetson-agx-thor-baseboard"
				(path ""
					(reference "C152")
					(unit 1)
				)
			)
		)
	)
	(symbol
		(lib_id "antmicroResistors0402:R_27R_0402")
		(at 259.08 107.95 0)
		(unit 1)
		(exclude_from_sim no)
		(in_bom yes)
		(on_board yes)
		(dnp no)
		(property "Reference" "R147"
			(at 264.16 107.315 0)
			(effects
				(font
					(size 1.27 1.27)
				)
				(justify left bottom)
			)
		)
		(property "Value" "R_27R_0402"
			(at 279.4 120.65 0)
			(effects
				(font
					(size 1.27 1.27)
					(thickness 0.15)
				)
				(justify left bottom)
				(hide yes)
			)
		)
		(property "Footprint" "antmicro-footprints:R_0402_1005Metric"
			(at 279.4 123.19 0)
			(effects
				(font
					(size 1.27 1.27)
					(thickness 0.15)
				)
				(justify left bottom)
				(hide yes)
			)
		)
		(property "Datasheet" "https://www.bourns.com/docs/product-datasheets/cr.pdf"
			(at 279.4 125.73 0)
			(effects
				(font
					(size 1.27 1.27)
					(thickness 0.15)
				)
				(justify left bottom)
				(hide yes)
			)
		)
		(property "Description" "SMD Chip Resistor, 27 ohm, ± 1%, 63 mW, 0402 [1005 Metric], Thick Film, General Purpose"
			(at 259.08 107.95 0)
			(effects
				(font
					(size 1.27 1.27)
				)
				(hide yes)
			)
		)
		(property "Manufacturer" "Bourns"
			(at 279.4 130.81 0)
			(effects
				(font
					(size 1.27 1.27)
					(thickness 0.15)
				)
				(justify left bottom)
				(hide yes)
			)
		)
		(property "MPN" "CR0402-FX-27R0GLF"
			(at 279.4 128.27 0)
			(effects
				(font
					(size 1.27 1.27)
					(thickness 0.15)
				)
				(justify left bottom)
				(hide yes)
			)
		)
		(property "Val" "27R"
			(at 255.27 107.315 0)
			(effects
				(font
					(size 1.27 1.27)
					(thickness 0.15)
				)
				(justify left bottom)
			)
		)
		(property "License" "Apache-2.0"
			(at 279.4 133.35 0)
			(effects
				(font
					(size 1.27 1.27)
					(thickness 0.15)
				)
				(justify left bottom)
				(hide yes)
			)
		)
		(property "Author" "Antmicro"
			(at 279.4 135.89 0)
			(effects
				(font
					(size 1.27 1.27)
					(thickness 0.15)
				)
				(justify left bottom)
				(hide yes)
			)
		)
		(property "Tolerance" "1%"
			(at 279.4 118.11 0)
			(effects
				(font
					(size 1.27 1.27)
				)
				(justify left bottom)
				(hide yes)
			)
		)
		(pin "1"
		)
		(pin "2"
		)
		(instances
			(project "usb_debug_pd"
				(path ""
					(reference "R?")
					(unit 1)
				)
			)
			(project "jetson-agx-thor-baseboard"
				(path ""
					(reference "R147")
					(unit 1)
				)
			)
		)
	)
	(symbol
		(lib_id "antmicropower:GND")
		(at 74.93 106.68 0)
		(unit 1)
		(exclude_from_sim no)
		(in_bom yes)
		(on_board yes)
		(dnp no)
		(property "Reference" "#PWR0488"
			(at 74.93 113.03 0)
			(effects
				(font
					(size 1.27 1.27)
				)
				(justify left bottom)
				(hide yes)
			)
		)
		(property "Value" "GND"
			(at 74.93 110.49 0)
			(effects
				(font
					(size 1.27 1.27)
					(thickness 0.15)
				)
			)
		)
		(property "Footprint" ""
			(at 83.82 114.3 0)
			(effects
				(font
					(size 1.27 1.27)
					(thickness 0.15)
				)
				(justify left bottom)
				(hide yes)
			)
		)
		(property "Datasheet" ""
			(at 83.82 119.38 0)
			(effects
				(font
					(size 1.27 1.27)
					(thickness 0.15)
				)
				(justify left bottom)
				(hide yes)
			)
		)
		(property "Description" ""
			(at 74.93 106.68 0)
			(effects
				(font
					(size 1.27 1.27)
				)
				(hide yes)
			)
		)
		(property "Author" "Antmicro"
			(at 83.82 114.3 0)
			(effects
				(font
					(size 1.27 1.27)
					(thickness 0.15)
				)
				(justify left bottom)
				(hide yes)
			)
		)
		(property "License" "Apache-2.0"
			(at 83.82 116.84 0)
			(effects
				(font
					(size 1.27 1.27)
					(thickness 0.15)
				)
				(justify left bottom)
				(hide yes)
			)
		)
		(pin "1"
		)
		(instances
			(project "usb_debug_pd"
				(path ""
					(reference "#PWR?")
					(unit 1)
				)
			)
			(project "jetson-agx-thor-baseboard"
				(path ""
					(reference "#PWR0488")
					(unit 1)
				)
			)
		)
	)
	(symbol
		(lib_id "antmicropower:GND")
		(at 149.86 208.28 0)
		(mirror y)
		(unit 1)
		(exclude_from_sim no)
		(in_bom yes)
		(on_board yes)
		(dnp no)
		(property "Reference" "#PWR0217"
			(at 149.86 214.63 0)
			(effects
				(font
					(size 1.27 1.27)
				)
				(justify left bottom)
				(hide yes)
			)
		)
		(property "Value" "GND"
			(at 149.86 212.09 0)
			(effects
				(font
					(size 1.27 1.27)
					(thickness 0.15)
				)
			)
		)
		(property "Footprint" ""
			(at 140.97 215.9 0)
			(effects
				(font
					(size 1.27 1.27)
					(thickness 0.15)
				)
				(justify left bottom)
				(hide yes)
			)
		)
		(property "Datasheet" ""
			(at 140.97 220.98 0)
			(effects
				(font
					(size 1.27 1.27)
					(thickness 0.15)
				)
				(justify left bottom)
				(hide yes)
			)
		)
		(property "Description" ""
			(at 149.86 208.28 0)
			(effects
				(font
					(size 1.27 1.27)
				)
				(hide yes)
			)
		)
		(property "Author" "Antmicro"
			(at 140.97 215.9 0)
			(effects
				(font
					(size 1.27 1.27)
					(thickness 0.15)
				)
				(justify left bottom)
				(hide yes)
			)
		)
		(property "License" "Apache-2.0"
			(at 140.97 218.44 0)
			(effects
				(font
					(size 1.27 1.27)
					(thickness 0.15)
				)
				(justify left bottom)
				(hide yes)
			)
		)
		(pin "1"
		)
		(instances
			(project "usb_debug_pd"
				(path ""
					(reference "#PWR?")
					(unit 1)
				)
			)
			(project "jetson-agx-thor-baseboard"
				(path ""
					(reference "#PWR0217")
					(unit 1)
				)
			)
		)
	)
	(symbol
		(lib_id "antmicropower:GND")
		(at 270.51 119.38 0)
		(mirror y)
		(unit 1)
		(exclude_from_sim no)
		(in_bom yes)
		(on_board yes)
		(dnp no)
		(property "Reference" "#PWR0269"
			(at 270.51 125.73 0)
			(effects
				(font
					(size 1.27 1.27)
				)
				(justify left bottom)
				(hide yes)
			)
		)
		(property "Value" "GND"
			(at 270.51 123.19 0)
			(effects
				(font
					(size 1.27 1.27)
					(thickness 0.15)
				)
			)
		)
		(property "Footprint" ""
			(at 261.62 127 0)
			(effects
				(font
					(size 1.27 1.27)
					(thickness 0.15)
				)
				(justify left bottom)
				(hide yes)
			)
		)
		(property "Datasheet" ""
			(at 261.62 132.08 0)
			(effects
				(font
					(size 1.27 1.27)
					(thickness 0.15)
				)
				(justify left bottom)
				(hide yes)
			)
		)
		(property "Description" ""
			(at 270.51 119.38 0)
			(effects
				(font
					(size 1.27 1.27)
				)
				(hide yes)
			)
		)
		(property "Author" "Antmicro"
			(at 261.62 127 0)
			(effects
				(font
					(size 1.27 1.27)
					(thickness 0.15)
				)
				(justify left bottom)
				(hide yes)
			)
		)
		(property "License" "Apache-2.0"
			(at 261.62 129.54 0)
			(effects
				(font
					(size 1.27 1.27)
					(thickness 0.15)
				)
				(justify left bottom)
				(hide yes)
			)
		)
		(pin "1"
		)
		(instances
			(project "usb_debug_pd"
				(path ""
					(reference "#PWR?")
					(unit 1)
				)
			)
			(project "jetson-agx-thor-baseboard"
				(path ""
					(reference "#PWR0269")
					(unit 1)
				)
			)
		)
	)
	(symbol
		(lib_id "antmicropower:GND")
		(at 39.37 219.71 0)
		(unit 1)
		(exclude_from_sim no)
		(in_bom yes)
		(on_board yes)
		(dnp no)
		(fields_autoplaced yes)
		(property "Reference" "#PWR0223"
			(at 39.37 226.06 0)
			(effects
				(font
					(size 1.27 1.27)
				)
				(justify left bottom)
				(hide yes)
			)
		)
		(property "Value" "GND"
			(at 39.37 223.52 0)
			(effects
				(font
					(size 1.27 1.27)
					(thickness 0.15)
				)
			)
		)
		(property "Footprint" ""
			(at 48.26 227.33 0)
			(effects
				(font
					(size 1.27 1.27)
					(thickness 0.15)
				)
				(justify left bottom)
				(hide yes)
			)
		)
		(property "Datasheet" ""
			(at 48.26 232.41 0)
			(effects
				(font
					(size 1.27 1.27)
					(thickness 0.15)
				)
				(justify left bottom)
				(hide yes)
			)
		)
		(property "Description" ""
			(at 39.37 219.71 0)
			(effects
				(font
					(size 1.27 1.27)
				)
				(hide yes)
			)
		)
		(property "Author" "Antmicro"
			(at 48.26 227.33 0)
			(effects
				(font
					(size 1.27 1.27)
					(thickness 0.15)
				)
				(justify left bottom)
				(hide yes)
			)
		)
		(property "License" "Apache-2.0"
			(at 48.26 229.87 0)
			(effects
				(font
					(size 1.27 1.27)
					(thickness 0.15)
				)
				(justify left bottom)
				(hide yes)
			)
		)
		(pin "1"
		)
		(instances
			(project "usb_debug_pd"
				(path ""
					(reference "#PWR?")
					(unit 1)
				)
			)
			(project "jetson-agx-thor-baseboard"
				(path ""
					(reference "#PWR0223")
					(unit 1)
				)
			)
		)
	)
	(symbol
		(lib_id "antmicroResistors0402:R_10k_0402")
		(at 335.28 201.93 180)
		(unit 1)
		(exclude_from_sim no)
		(in_bom yes)
		(on_board yes)
		(dnp no)
		(property "Reference" "R98"
			(at 327.66 200.66 0)
			(effects
				(font
					(size 1.27 1.27)
					(thickness 0.15)
				)
			)
		)
		(property "Value" "R_10k_0402"
			(at 314.96 189.23 0)
			(effects
				(font
					(size 1.27 1.27)
					(thickness 0.15)
				)
				(justify left bottom)
				(hide yes)
			)
		)
		(property "Footprint" "antmicro-footprints:R_0402_1005Metric"
			(at 314.96 186.69 0)
			(effects
				(font
					(size 1.27 1.27)
					(thickness 0.15)
				)
				(justify left bottom)
				(hide yes)
			)
		)
		(property "Datasheet" "https://www.bourns.com/docs/product-datasheets/cr.pdf"
			(at 314.96 184.15 0)
			(effects
				(font
					(size 1.27 1.27)
					(thickness 0.15)
				)
				(justify left bottom)
				(hide yes)
			)
		)
		(property "Description" "SMD Chip Resistor, 10 kohm, ± 1%, 62.5 mW, 0402 [1005 Metric], Thick Film, General Purpose"
			(at 335.28 201.93 0)
			(effects
				(font
					(size 1.27 1.27)
				)
				(hide yes)
			)
		)
		(property "MPN" "CR0402-FX-1002GLF"
			(at 314.96 181.61 0)
			(effects
				(font
					(size 1.27 1.27)
					(thickness 0.15)
				)
				(justify left bottom)
				(hide yes)
			)
		)
		(property "Manufacturer" "Bourns"
			(at 314.96 179.07 0)
			(effects
				(font
					(size 1.27 1.27)
					(thickness 0.15)
				)
				(justify left bottom)
				(hide yes)
			)
		)
		(property "License" "Apache-2.0"
			(at 314.96 176.53 0)
			(effects
				(font
					(size 1.27 1.27)
					(thickness 0.15)
				)
				(justify left bottom)
				(hide yes)
			)
		)
		(property "Author" "Antmicro"
			(at 314.96 173.99 0)
			(effects
				(font
					(size 1.27 1.27)
					(thickness 0.15)
				)
				(justify left bottom)
				(hide yes)
			)
		)
		(property "Val" "10k"
			(at 336.55 200.66 0)
			(effects
				(font
					(size 1.27 1.27)
					(thickness 0.15)
				)
			)
		)
		(property "Tolerance" "1%"
			(at 314.96 191.77 0)
			(effects
				(font
					(size 1.27 1.27)
				)
				(justify left bottom)
				(hide yes)
			)
		)
		(pin "1"
		)
		(pin "2"
		)
		(instances
			(project "usb_debug_pd"
				(path ""
					(reference "R?")
					(unit 1)
				)
			)
			(project "jetson-agx-thor-baseboard"
				(path ""
					(reference "R98")
					(unit 1)
				)
			)
		)
	)
	(symbol
		(lib_id "antmicropower:GND")
		(at 275.59 119.38 0)
		(mirror y)
		(unit 1)
		(exclude_from_sim no)
		(in_bom yes)
		(on_board yes)
		(dnp no)
		(property "Reference" "#PWR0270"
			(at 275.59 125.73 0)
			(effects
				(font
					(size 1.27 1.27)
				)
				(justify left bottom)
				(hide yes)
			)
		)
		(property "Value" "GND"
			(at 275.59 123.19 0)
			(effects
				(font
					(size 1.27 1.27)
					(thickness 0.15)
				)
			)
		)
		(property "Footprint" ""
			(at 266.7 127 0)
			(effects
				(font
					(size 1.27 1.27)
					(thickness 0.15)
				)
				(justify left bottom)
				(hide yes)
			)
		)
		(property "Datasheet" ""
			(at 266.7 132.08 0)
			(effects
				(font
					(size 1.27 1.27)
					(thickness 0.15)
				)
				(justify left bottom)
				(hide yes)
			)
		)
		(property "Description" ""
			(at 275.59 119.38 0)
			(effects
				(font
					(size 1.27 1.27)
				)
				(hide yes)
			)
		)
		(property "Author" "Antmicro"
			(at 266.7 127 0)
			(effects
				(font
					(size 1.27 1.27)
					(thickness 0.15)
				)
				(justify left bottom)
				(hide yes)
			)
		)
		(property "License" "Apache-2.0"
			(at 266.7 129.54 0)
			(effects
				(font
					(size 1.27 1.27)
					(thickness 0.15)
				)
				(justify left bottom)
				(hide yes)
			)
		)
		(pin "1"
		)
		(instances
			(project "usb_debug_pd"
				(path ""
					(reference "#PWR?")
					(unit 1)
				)
			)
			(project "jetson-agx-thor-baseboard"
				(path ""
					(reference "#PWR0270")
					(unit 1)
				)
			)
		)
	)
	(symbol
		(lib_id "antmicroResistors0402:R_1k_0402")
		(at 86.36 110.49 270)
		(mirror x)
		(unit 1)
		(exclude_from_sim no)
		(in_bom yes)
		(on_board yes)
		(dnp no)
		(property "Reference" "R113"
			(at 84.836 107.188 90)
			(effects
				(font
					(size 1.27 1.27)
					(thickness 0.15)
				)
				(justify right)
			)
		)
		(property "Value" "R_1k_0402"
			(at 73.66 90.17 0)
			(effects
				(font
					(size 1.27 1.27)
					(thickness 0.15)
				)
				(justify left bottom)
				(hide yes)
			)
		)
		(property "Footprint" "antmicro-footprints:R_0402_1005Metric"
			(at 71.12 90.17 0)
			(effects
				(font
					(size 1.27 1.27)
					(thickness 0.15)
				)
				(justify left bottom)
				(hide yes)
			)
		)
		(property "Datasheet" "https://www.bourns.com/docs/product-datasheets/cr.pdf"
			(at 68.58 90.17 0)
			(effects
				(font
					(size 1.27 1.27)
					(thickness 0.15)
				)
				(justify left bottom)
				(hide yes)
			)
		)
		(property "Description" "SMD Chip Resistor, 1 kohm, ± 1%, 63 mW, 0402 [1005 Metric], Thick Film, General Purpose"
			(at 86.36 110.49 0)
			(effects
				(font
					(size 1.27 1.27)
				)
				(hide yes)
			)
		)
		(property "MPN" "CR0402-FX-1001GLF"
			(at 66.04 90.17 0)
			(effects
				(font
					(size 1.27 1.27)
					(thickness 0.15)
				)
				(justify left bottom)
				(hide yes)
			)
		)
		(property "Manufacturer" "Bourns"
			(at 63.5 90.17 0)
			(effects
				(font
					(size 1.27 1.27)
					(thickness 0.15)
				)
				(justify left bottom)
				(hide yes)
			)
		)
		(property "License" "Apache-2.0"
			(at 60.96 90.17 0)
			(effects
				(font
					(size 1.27 1.27)
					(thickness 0.15)
				)
				(justify left bottom)
				(hide yes)
			)
		)
		(property "Author" "Antmicro"
			(at 58.42 90.17 0)
			(effects
				(font
					(size 1.27 1.27)
					(thickness 0.15)
				)
				(justify left bottom)
				(hide yes)
			)
		)
		(property "Val" "1k"
			(at 84.836 109.728 90)
			(effects
				(font
					(size 1.27 1.27)
					(thickness 0.15)
				)
				(justify right)
			)
		)
		(property "Tolerance" "1%"
			(at 76.2 90.17 0)
			(effects
				(font
					(size 1.27 1.27)
				)
				(justify left bottom)
				(hide yes)
			)
		)
		(pin "2"
		)
		(pin "1"
		)
		(instances
			(project "usb_debug_pd"
				(path ""
					(reference "R?")
					(unit 1)
				)
			)
			(project "jetson-agx-thor-baseboard"
				(path ""
					(reference "R113")
					(unit 1)
				)
			)
		)
	)
	(symbol
		(lib_id "antmicroPMICPowerDistributionSwitchesLoadDrivers:AP22615A_TSOT26")
		(at 287.02 31.75 0)
		(unit 1)
		(exclude_from_sim no)
		(in_bom yes)
		(on_board yes)
		(dnp no)
		(property "Reference" "U40"
			(at 294.64 25.4 0)
			(effects
				(font
					(size 1.27 1.27)
				)
			)
		)
		(property "Value" "AP22615A_TSOT26"
			(at 317.5 36.83 0)
			(effects
				(font
					(size 1.27 1.27)
					(thickness 0.15)
				)
				(justify left bottom)
				(hide yes)
			)
		)
		(property "Footprint" "antmicro-footprints:TSOT23-6"
			(at 317.5 39.37 0)
			(effects
				(font
					(size 1.27 1.27)
					(thickness 0.15)
				)
				(justify left bottom)
				(hide yes)
			)
		)
		(property "Datasheet" "https://www.mouser.com/datasheet/2/115/DIOD_S_A0008958405_1-2543193.pdf"
			(at 317.5 41.91 0)
			(effects
				(font
					(size 1.27 1.27)
					(thickness 0.15)
				)
				(justify left bottom)
				(hide yes)
			)
		)
		(property "Description" "Power Load Distribution Switch, High Side, Active High, 1 Output, 5.5 V, 3.6 A, 0.04 ohm, TSOT-26-6"
			(at 287.02 31.75 0)
			(effects
				(font
					(size 1.27 1.27)
				)
				(hide yes)
			)
		)
		(property "MPN" "AP22615AWU-7"
			(at 294.64 27.94 0)
			(effects
				(font
					(size 1.27 1.27)
					(thickness 0.15)
				)
			)
		)
		(property "Manufacturer" "Diodes Incorporated"
			(at 317.5 46.99 0)
			(effects
				(font
					(size 1.27 1.27)
					(thickness 0.15)
				)
				(justify left bottom)
				(hide yes)
			)
		)
		(property "Author" "Antmicro"
			(at 317.5 49.53 0)
			(effects
				(font
					(size 1.27 1.27)
					(thickness 0.15)
				)
				(justify left bottom)
				(hide yes)
			)
		)
		(property "License" "Apache-2.0"
			(at 317.5 52.07 0)
			(effects
				(font
					(size 1.27 1.27)
					(thickness 0.15)
				)
				(justify left bottom)
				(hide yes)
			)
		)
		(pin "1"
		)
		(pin "2"
		)
		(pin "3"
		)
		(pin "4"
		)
		(pin "5"
		)
		(pin "6"
		)
		(instances
			(project "usb_debug_pd"
				(path ""
					(reference "U?")
					(unit 1)
				)
			)
			(project "jetson-agx-thor-baseboard"
				(path ""
					(reference "U40")
					(unit 1)
				)
			)
		)
	)
	(symbol
		(lib_id "antmicroResistors0402:R_100k_0402")
		(at 97.79 127 270)
		(mirror x)
		(unit 1)
		(exclude_from_sim no)
		(in_bom yes)
		(on_board yes)
		(dnp no)
		(fields_autoplaced yes)
		(property "Reference" "R115"
			(at 95.25 123.19 90)
			(effects
				(font
					(size 1.27 1.27)
					(thickness 0.15)
				)
				(justify right)
			)
		)
		(property "Value" "R_100k_0402"
			(at 85.09 106.68 0)
			(effects
				(font
					(size 1.27 1.27)
					(thickness 0.15)
				)
				(justify left bottom)
				(hide yes)
			)
		)
		(property "Footprint" "antmicro-footprints:R_0402_1005Metric"
			(at 82.55 106.68 0)
			(effects
				(font
					(size 1.27 1.27)
					(thickness 0.15)
				)
				(justify left bottom)
				(hide yes)
			)
		)
		(property "Datasheet" "https://www.bourns.com/docs/product-datasheets/cr.pdf"
			(at 80.01 106.68 0)
			(effects
				(font
					(size 1.27 1.27)
					(thickness 0.15)
				)
				(justify left bottom)
				(hide yes)
			)
		)
		(property "Description" "SMD Chip Resistor, 100 kohm, ± 1%, 62.5 mW, 0402 [1005 Metric], Thick Film, General Purpose"
			(at 97.79 127 0)
			(effects
				(font
					(size 1.27 1.27)
				)
				(hide yes)
			)
		)
		(property "MPN" "CR0402-FX-1003GLF"
			(at 77.47 106.68 0)
			(effects
				(font
					(size 1.27 1.27)
					(thickness 0.15)
				)
				(justify left bottom)
				(hide yes)
			)
		)
		(property "Manufacturer" "Bourns"
			(at 74.93 106.68 0)
			(effects
				(font
					(size 1.27 1.27)
					(thickness 0.15)
				)
				(justify left bottom)
				(hide yes)
			)
		)
		(property "License" "Apache-2.0"
			(at 72.39 106.68 0)
			(effects
				(font
					(size 1.27 1.27)
					(thickness 0.15)
				)
				(justify left bottom)
				(hide yes)
			)
		)
		(property "Author" "Antmicro"
			(at 69.85 106.68 0)
			(effects
				(font
					(size 1.27 1.27)
					(thickness 0.15)
				)
				(justify left bottom)
				(hide yes)
			)
		)
		(property "Val" "100k"
			(at 95.25 125.73 90)
			(effects
				(font
					(size 1.27 1.27)
					(thickness 0.15)
				)
				(justify right)
			)
		)
		(property "Tolerance" "1%"
			(at 87.63 106.68 0)
			(effects
				(font
					(size 1.27 1.27)
				)
				(justify left bottom)
				(hide yes)
			)
		)
		(pin "2"
		)
		(pin "1"
		)
		(instances
			(project "usb_debug_pd"
				(path ""
					(reference "R?")
					(unit 1)
				)
			)
			(project "jetson-agx-thor-baseboard"
				(path ""
					(reference "R115")
					(unit 1)
				)
			)
		)
	)
	(symbol
		(lib_id "antmicroInterfaceControllers:FT230X_QFN")
		(at 194.31 99.06 0)
		(mirror y)
		(unit 1)
		(exclude_from_sim no)
		(in_bom yes)
		(on_board yes)
		(dnp no)
		(fields_autoplaced yes)
		(property "Reference" "U34"
			(at 182.88 124.46 0)
			(effects
				(font
					(size 1.27 1.27)
				)
			)
		)
		(property "Value" "FT230X_QFN"
			(at 154.94 109.22 0)
			(effects
				(font
					(size 1.27 1.27)
					(thickness 0.15)
				)
				(justify left bottom)
				(hide yes)
			)
		)
		(property "Footprint" "antmicro-footprints:QFN-16-1EP_4x4mm_P0.65mm"
			(at 154.94 111.76 0)
			(effects
				(font
					(size 1.27 1.27)
					(thickness 0.15)
				)
				(justify left bottom)
				(hide yes)
			)
		)
		(property "Datasheet" "https://ftdichip.com/wp-content/uploads/2021/10/DS_FT230X.pdf"
			(at 154.94 114.3 0)
			(effects
				(font
					(size 1.27 1.27)
					(thickness 0.15)
				)
				(justify left bottom)
				(hide yes)
			)
		)
		(property "Description" "USB Interface, USB-UART Converter, USB 2.0, 2.97 V, 5.5 V, QFN, 16 Pins"
			(at 194.31 99.06 0)
			(effects
				(font
					(size 1.27 1.27)
				)
				(hide yes)
			)
		)
		(property "Manufacturer" "FTDI Chip"
			(at 154.94 116.84 0)
			(effects
				(font
					(size 1.27 1.27)
					(thickness 0.15)
				)
				(justify left bottom)
				(hide yes)
			)
		)
		(property "MPN" "FT230XQ-R"
			(at 182.88 127 0)
			(effects
				(font
					(size 1.27 1.27)
					(thickness 0.15)
				)
			)
		)
		(property "Author" "Antmicro"
			(at 154.94 121.92 0)
			(effects
				(font
					(size 1.27 1.27)
					(thickness 0.15)
				)
				(justify left bottom)
				(hide yes)
			)
		)
		(property "License" "Apache-2.0"
			(at 154.94 124.46 0)
			(effects
				(font
					(size 1.27 1.27)
					(thickness 0.15)
				)
				(justify left bottom)
				(hide yes)
			)
		)
		(pin "1"
		)
		(pin "10"
		)
		(pin "11"
		)
		(pin "12"
		)
		(pin "13"
		)
		(pin "14"
		)
		(pin "15"
		)
		(pin "16"
		)
		(pin "17"
		)
		(pin "2"
		)
		(pin "3"
		)
		(pin "4"
		)
		(pin "5"
		)
		(pin "6"
		)
		(pin "7"
		)
		(pin "8"
		)
		(pin "9"
		)
		(instances
			(project "usb_debug_pd"
				(path ""
					(reference "U?")
					(unit 1)
				)
			)
			(project "jetson-agx-thor-baseboard"
				(path ""
					(reference "U34")
					(unit 1)
				)
			)
		)
	)
	(symbol
		(lib_id "antmicroCapacitors0402:C_100n_0402")
		(at 162.56 66.04 270)
		(unit 1)
		(exclude_from_sim no)
		(in_bom yes)
		(on_board yes)
		(dnp no)
		(fields_autoplaced yes)
		(property "Reference" "C44"
			(at 160.02 67.3163 90)
			(effects
				(font
					(size 1.27 1.27)
				)
				(justify right)
			)
		)
		(property "Value" "C_100n_0402"
			(at 152.4 86.36 0)
			(effects
				(font
					(size 1.27 1.27)
					(thickness 0.15)
				)
				(justify left bottom)
				(hide yes)
			)
		)
		(property "Footprint" "antmicro-footprints:C_0402_1005Metric"
			(at 149.86 86.36 0)
			(effects
				(font
					(size 1.27 1.27)
					(thickness 0.15)
				)
				(justify left bottom)
				(hide yes)
			)
		)
		(property "Datasheet" "https://www.murata.com/products/productdetail?partno=GRM155R61H104KE14%23"
			(at 147.32 86.36 0)
			(effects
				(font
					(size 1.27 1.27)
					(thickness 0.15)
				)
				(justify left bottom)
				(hide yes)
			)
		)
		(property "Description" "SMD Multilayer Ceramic Capacitor, 0.1 µF, 50 V, 0402 [1005 Metric], ± 10%, X5R, GRM Series"
			(at 162.56 66.04 0)
			(effects
				(font
					(size 1.27 1.27)
				)
				(hide yes)
			)
		)
		(property "Manufacturer" "Murata"
			(at 142.24 86.36 0)
			(effects
				(font
					(size 1.27 1.27)
					(thickness 0.15)
				)
				(justify left bottom)
				(hide yes)
			)
		)
		(property "MPN" "GRM155R61H104KE14D"
			(at 144.78 86.36 0)
			(effects
				(font
					(size 1.27 1.27)
					(thickness 0.15)
				)
				(justify left bottom)
				(hide yes)
			)
		)
		(property "Val" "100n"
			(at 160.02 69.8563 90)
			(effects
				(font
					(size 1.27 1.27)
					(thickness 0.15)
				)
				(justify right)
			)
		)
		(property "License" "Apache-2.0"
			(at 139.7 86.36 0)
			(effects
				(font
					(size 1.27 1.27)
					(thickness 0.15)
				)
				(justify left bottom)
				(hide yes)
			)
		)
		(property "Author" "Antmicro"
			(at 137.16 86.36 0)
			(effects
				(font
					(size 1.27 1.27)
					(thickness 0.15)
				)
				(justify left bottom)
				(hide yes)
			)
		)
		(property "Voltage" "50V"
			(at 134.62 86.36 0)
			(effects
				(font
					(size 1.27 1.27)
				)
				(justify left bottom)
				(hide yes)
			)
		)
		(property "Dielectric" "X5R"
			(at 132.08 86.36 0)
			(effects
				(font
					(size 1.27 1.27)
				)
				(justify left bottom)
				(hide yes)
			)
		)
		(pin "1"
		)
		(pin "2"
		)
		(instances
			(project "jetson-agx-thor-baseboard"
				(path ""
					(reference "C44")
					(unit 1)
				)
			)
		)
	)
	(symbol
		(lib_id "antmicropower:+3V3")
		(at 311.15 209.55 0)
		(unit 1)
		(exclude_from_sim no)
		(in_bom yes)
		(on_board yes)
		(dnp no)
		(fields_autoplaced yes)
		(property "Reference" "#PWR0218"
			(at 326.39 209.55 0)
			(effects
				(font
					(size 1.27 1.27)
					(thickness 0.15)
				)
				(justify left bottom)
				(hide yes)
			)
		)
		(property "Value" "FLASH_PWR"
			(at 311.15 204.47 0)
			(effects
				(font
					(size 1.27 1.27)
					(thickness 0.15)
				)
			)
		)
		(property "Footprint" ""
			(at 326.39 217.17 0)
			(effects
				(font
					(size 1.27 1.27)
					(thickness 0.15)
				)
				(justify left bottom)
				(hide yes)
			)
		)
		(property "Datasheet" ""
			(at 326.39 219.71 0)
			(effects
				(font
					(size 1.27 1.27)
					(thickness 0.15)
				)
				(justify left bottom)
				(hide yes)
			)
		)
		(property "Description" ""
			(at 311.15 209.55 0)
			(effects
				(font
					(size 1.27 1.27)
				)
				(hide yes)
			)
		)
		(property "Author" "Antmicro"
			(at 326.39 212.09 0)
			(effects
				(font
					(size 1.27 1.27)
					(thickness 0.15)
				)
				(justify left bottom)
				(hide yes)
			)
		)
		(property "License" "Apache-2.0"
			(at 326.39 214.63 0)
			(effects
				(font
					(size 1.27 1.27)
					(thickness 0.15)
				)
				(justify left bottom)
				(hide yes)
			)
		)
		(pin "1"
		)
		(instances
			(project "usb_debug_pd"
				(path ""
					(reference "#PWR?")
					(unit 1)
				)
			)
			(project "jetson-agx-thor-baseboard"
				(path ""
					(reference "#PWR0218")
					(unit 1)
				)
			)
		)
	)
	(symbol
		(lib_id "antmicroUSBConnectors:USB-C_Kycon_KUSBX-SL2-CS1N24-B-TR")
		(at 323.85 66.04 0)
		(mirror y)
		(unit 1)
		(exclude_from_sim no)
		(in_bom yes)
		(on_board yes)
		(dnp no)
		(property "Reference" "J7"
			(at 337.185 58.42 0)
			(effects
				(font
					(size 1.27 1.27)
					(thickness 0.15)
				)
			)
		)
		(property "Value" "USB-C_Kycon_KUSBX-SL2-CS1N24-B-TR"
			(at 280.67 71.12 0)
			(effects
				(font
					(size 1.27 1.27)
					(thickness 0.15)
				)
				(justify left bottom)
				(hide yes)
			)
		)
		(property "Footprint" "antmicro-footprints:USB-C_Receptacle_Kycon_KUSBX-SL2-CS1N24-B-TR"
			(at 280.67 73.66 0)
			(effects
				(font
					(size 1.27 1.27)
					(thickness 0.15)
				)
				(justify left bottom)
				(hide yes)
			)
		)
		(property "Datasheet" "https://www.kycon.com/Pub_Eng_Draw/KUSBX-SL2-CS1N24-B-TR.pdf"
			(at 280.67 76.2 0)
			(effects
				(font
					(size 1.27 1.27)
					(thickness 0.15)
				)
				(justify left bottom)
				(hide yes)
			)
		)
		(property "Description" "USB-C (USB TYPE-C) USB 3.2 Gen 2 (USB 3.1 Gen 2, Superspeed + (USB 3.1)) USB PD Receptacle Connector 24 Position Surface Mount"
			(at 280.67 88.9 0)
			(effects
				(font
					(size 1.27 1.27)
				)
				(justify left bottom)
				(hide yes)
			)
		)
		(property "MPN" "KUSBX-SL2-CS1N24-B-TR"
			(at 337.185 60.96 0)
			(effects
				(font
					(size 1.27 1.27)
					(thickness 0.15)
				)
			)
		)
		(property "Manufacturer" "Kycon"
			(at 280.67 81.28 0)
			(effects
				(font
					(size 1.27 1.27)
					(thickness 0.15)
				)
				(justify left bottom)
				(hide yes)
			)
		)
		(property "License" "Apache-2.0"
			(at 280.67 83.82 0)
			(effects
				(font
					(size 1.27 1.27)
					(thickness 0.15)
				)
				(justify left bottom)
				(hide yes)
			)
		)
		(property "Author" "Antmicro"
			(at 280.67 86.36 0)
			(effects
				(font
					(size 1.27 1.27)
					(thickness 0.15)
				)
				(justify left bottom)
				(hide yes)
			)
		)
		(pin "A6"
		)
		(pin "A2"
		)
		(pin "SH"
		)
		(pin "A1"
		)
		(pin "B12"
		)
		(pin "B7"
		)
		(pin "A12"
		)
		(pin "A8"
		)
		(pin "B1"
		)
		(pin "B8"
		)
		(pin "A3"
		)
		(pin "B10"
		)
		(pin "B3"
		)
		(pin "A7"
		)
		(pin "A11"
		)
		(pin "B5"
		)
		(pin "B9"
		)
		(pin "A5"
		)
		(pin "A9"
		)
		(pin "B4"
		)
		(pin "A4"
		)
		(pin "B6"
		)
		(pin "B2"
		)
		(pin "B11"
		)
		(pin "A10"
		)
		(instances
			(project "usb_debug_pd"
				(path ""
					(reference "J?")
					(unit 1)
				)
			)
			(project "jetson-agx-thor-baseboard"
				(path ""
					(reference "J7")
					(unit 1)
				)
			)
		)
	)
	(symbol
		(lib_id "antmicropower:GND")
		(at 153.67 72.39 0)
		(unit 1)
		(exclude_from_sim no)
		(in_bom yes)
		(on_board yes)
		(dnp no)
		(property "Reference" "#PWR0247"
			(at 153.67 78.74 0)
			(effects
				(font
					(size 1.27 1.27)
				)
				(justify left bottom)
				(hide yes)
			)
		)
		(property "Value" "GND"
			(at 153.67 76.2 0)
			(effects
				(font
					(size 1.27 1.27)
					(thickness 0.15)
				)
			)
		)
		(property "Footprint" ""
			(at 162.56 80.01 0)
			(effects
				(font
					(size 1.27 1.27)
					(thickness 0.15)
				)
				(justify left bottom)
				(hide yes)
			)
		)
		(property "Datasheet" ""
			(at 162.56 85.09 0)
			(effects
				(font
					(size 1.27 1.27)
					(thickness 0.15)
				)
				(justify left bottom)
				(hide yes)
			)
		)
		(property "Description" ""
			(at 153.67 72.39 0)
			(effects
				(font
					(size 1.27 1.27)
				)
				(hide yes)
			)
		)
		(property "Author" "Antmicro"
			(at 162.56 80.01 0)
			(effects
				(font
					(size 1.27 1.27)
					(thickness 0.15)
				)
				(justify left bottom)
				(hide yes)
			)
		)
		(property "License" "Apache-2.0"
			(at 162.56 82.55 0)
			(effects
				(font
					(size 1.27 1.27)
					(thickness 0.15)
				)
				(justify left bottom)
				(hide yes)
			)
		)
		(pin "1"
		)
		(instances
			(project "usb_debug_pd"
				(path ""
					(reference "#PWR?")
					(unit 1)
				)
			)
			(project "jetson-agx-thor-baseboard"
				(path ""
					(reference "#PWR0247")
					(unit 1)
				)
			)
		)
	)
	(symbol
		(lib_id "antmicroCapacitors0402:C_100n_0402")
		(at 199.39 118.11 90)
		(mirror x)
		(unit 1)
		(exclude_from_sim no)
		(in_bom yes)
		(on_board yes)
		(dnp no)
		(property "Reference" "C140"
			(at 201.295 119.38 90)
			(effects
				(font
					(size 1.27 1.27)
				)
				(justify right)
			)
		)
		(property "Value" "C_100n_0402"
			(at 209.55 138.43 0)
			(effects
				(font
					(size 1.27 1.27)
					(thickness 0.15)
				)
				(justify left bottom)
				(hide yes)
			)
		)
		(property "Footprint" "antmicro-footprints:C_0402_1005Metric"
			(at 212.09 138.43 0)
			(effects
				(font
					(size 1.27 1.27)
					(thickness 0.15)
				)
				(justify left bottom)
				(hide yes)
			)
		)
		(property "Datasheet" "https://www.murata.com/products/productdetail?partno=GRM155R61H104KE14%23"
			(at 214.63 138.43 0)
			(effects
				(font
					(size 1.27 1.27)
					(thickness 0.15)
				)
				(justify left bottom)
				(hide yes)
			)
		)
		(property "Description" "SMD Multilayer Ceramic Capacitor, 0.1 µF, 50 V, 0402 [1005 Metric], ± 10%, X5R, GRM Series"
			(at 199.39 118.11 0)
			(effects
				(font
					(size 1.27 1.27)
				)
				(hide yes)
			)
		)
		(property "Manufacturer" "Murata"
			(at 219.71 138.43 0)
			(effects
				(font
					(size 1.27 1.27)
					(thickness 0.15)
				)
				(justify left bottom)
				(hide yes)
			)
		)
		(property "MPN" "GRM155R61H104KE14D"
			(at 217.17 138.43 0)
			(effects
				(font
					(size 1.27 1.27)
					(thickness 0.15)
				)
				(justify left bottom)
				(hide yes)
			)
		)
		(property "Val" "100n"
			(at 201.295 121.92 90)
			(effects
				(font
					(size 1.27 1.27)
					(thickness 0.15)
				)
				(justify right)
			)
		)
		(property "License" "Apache-2.0"
			(at 222.25 138.43 0)
			(effects
				(font
					(size 1.27 1.27)
					(thickness 0.15)
				)
				(justify left bottom)
				(hide yes)
			)
		)
		(property "Author" "Antmicro"
			(at 224.79 138.43 0)
			(effects
				(font
					(size 1.27 1.27)
					(thickness 0.15)
				)
				(justify left bottom)
				(hide yes)
			)
		)
		(property "Voltage" "50V"
			(at 227.33 138.43 0)
			(effects
				(font
					(size 1.27 1.27)
				)
				(justify left bottom)
				(hide yes)
			)
		)
		(property "Dielectric" "X5R"
			(at 229.87 138.43 0)
			(effects
				(font
					(size 1.27 1.27)
				)
				(justify left bottom)
				(hide yes)
			)
		)
		(pin "1"
		)
		(pin "2"
		)
		(instances
			(project "usb_debug_pd"
				(path ""
					(reference "C?")
					(unit 1)
				)
			)
			(project "jetson-agx-thor-baseboard"
				(path ""
					(reference "C140")
					(unit 1)
				)
			)
		)
	)
	(symbol
		(lib_id "antmicroTestPoints:TP_0.75mm_SMD")
		(at 251.46 255.27 0)
		(unit 1)
		(exclude_from_sim no)
		(in_bom no)
		(on_board yes)
		(dnp no)
		(property "Reference" "TP13"
			(at 255.27 255.905 0)
			(effects
				(font
					(size 1.27 1.27)
				)
				(justify left bottom)
			)
		)
		(property "Value" "TP_0.75mm_SMD"
			(at 261.62 259.08 0)
			(effects
				(font
					(size 1.27 1.27)
					(thickness 0.15)
				)
				(justify left bottom)
				(hide yes)
			)
		)
		(property "Footprint" "antmicro-footprints:TP_SMD_0.75mm"
			(at 261.62 261.62 0)
			(effects
				(font
					(size 1.27 1.27)
					(thickness 0.15)
				)
				(justify left bottom)
				(hide yes)
			)
		)
		(property "Datasheet" ""
			(at 269.24 267.97 0)
			(effects
				(font
					(size 1.27 1.27)
					(thickness 0.15)
				)
				(justify left bottom)
				(hide yes)
			)
		)
		(property "Description" "SMT test point"
			(at 251.46 255.27 0)
			(effects
				(font
					(size 1.27 1.27)
				)
				(hide yes)
			)
		)
		(property "MPN" ""
			(at 262.255 266.7 0)
			(effects
				(font
					(size 1.27 1.27)
					(thickness 0.15)
				)
				(justify left bottom)
				(hide yes)
			)
		)
		(property "Manufacturer" ""
			(at 262.255 261.62 0)
			(effects
				(font
					(size 1.27 1.27)
					(thickness 0.15)
				)
				(justify left bottom)
				(hide yes)
			)
		)
		(property "Author" "Antmicro"
			(at 261.62 264.16 0)
			(effects
				(font
					(size 1.27 1.27)
					(thickness 0.15)
				)
				(justify left bottom)
				(hide yes)
			)
		)
		(property "License" "Apache-2.0"
			(at 261.62 266.7 0)
			(effects
				(font
					(size 1.27 1.27)
					(thickness 0.15)
				)
				(justify left bottom)
				(hide yes)
			)
		)
		(pin "1"
		)
		(instances
			(project "usb_debug_pd"
				(path ""
					(reference "TP?")
					(unit 1)
				)
			)
			(project "jetson-agx-thor-baseboard"
				(path ""
					(reference "TP13")
					(unit 1)
				)
			)
		)
	)
	(symbol
		(lib_id "antmicroResistors0402:R_15k_0402")
		(at 158.75 218.44 0)
		(unit 1)
		(exclude_from_sim no)
		(in_bom yes)
		(on_board yes)
		(dnp no)
		(property "Reference" "R31"
			(at 165.862 217.17 0)
			(effects
				(font
					(size 1.27 1.27)
					(thickness 0.15)
				)
			)
		)
		(property "Value" "R_15k_0402"
			(at 179.07 231.14 0)
			(effects
				(font
					(size 1.27 1.27)
					(thickness 0.15)
				)
				(justify left bottom)
				(hide yes)
			)
		)
		(property "Footprint" "antmicro-footprints:R_0402_1005Metric"
			(at 179.07 233.68 0)
			(effects
				(font
					(size 1.27 1.27)
					(thickness 0.15)
				)
				(justify left bottom)
				(hide yes)
			)
		)
		(property "Datasheet" "https://www.bourns.com/docs/product-datasheets/cr.pdf"
			(at 179.07 236.22 0)
			(effects
				(font
					(size 1.27 1.27)
					(thickness 0.15)
				)
				(justify left bottom)
				(hide yes)
			)
		)
		(property "Description" "SMD Chip Resistor, 15 kohm, ± 1%, 62.5 mW, 0402 [1005 Metric], Thick Film, General Purpose"
			(at 179.07 248.92 0)
			(effects
				(font
					(size 1.27 1.27)
				)
				(justify left bottom)
				(hide yes)
			)
		)
		(property "MPN" "CR0402-FX-1502GLF"
			(at 179.07 238.76 0)
			(effects
				(font
					(size 1.27 1.27)
					(thickness 0.15)
				)
				(justify left bottom)
				(hide yes)
			)
		)
		(property "Manufacturer" "Bourns"
			(at 179.07 241.3 0)
			(effects
				(font
					(size 1.27 1.27)
					(thickness 0.15)
				)
				(justify left bottom)
				(hide yes)
			)
		)
		(property "License" "Apache-2.0"
			(at 179.07 243.84 0)
			(effects
				(font
					(size 1.27 1.27)
					(thickness 0.15)
				)
				(justify left bottom)
				(hide yes)
			)
		)
		(property "Author" "Antmicro"
			(at 179.07 246.38 0)
			(effects
				(font
					(size 1.27 1.27)
					(thickness 0.15)
				)
				(justify left bottom)
				(hide yes)
			)
		)
		(property "Val" "15k"
			(at 157.48 217.17 0)
			(effects
				(font
					(size 1.27 1.27)
					(thickness 0.15)
				)
			)
		)
		(property "Tolerance" "1%"
			(at 179.07 228.6 0)
			(effects
				(font
					(size 1.27 1.27)
				)
				(justify left bottom)
				(hide yes)
			)
		)
		(pin "1"
		)
		(pin "2"
		)
		(instances
			(project "usb_debug_pd"
				(path ""
					(reference "R?")
					(unit 1)
				)
			)
			(project ""
				(path ""
					(reference "R31")
					(unit 1)
				)
			)
		)
	)
	(symbol
		(lib_id "antmicroDiodesRectifiersSingle:RB521S30T1G")
		(at 351.79 194.31 180)
		(unit 1)
		(exclude_from_sim no)
		(in_bom yes)
		(on_board yes)
		(dnp no)
		(fields_autoplaced yes)
		(property "Reference" "D17"
			(at 349.25 187.96 0)
			(effects
				(font
					(size 1.27 1.27)
				)
			)
		)
		(property "Value" "RB521S30T1G"
			(at 328.93 179.07 0)
			(effects
				(font
					(size 1.27 1.27)
					(thickness 0.15)
				)
				(justify left bottom)
				(hide yes)
			)
		)
		(property "Footprint" "antmicro-footprints:SOD-523"
			(at 328.93 184.15 0)
			(effects
				(font
					(size 1.27 1.27)
					(thickness 0.15)
				)
				(justify left bottom)
				(hide yes)
			)
		)
		(property "Datasheet" "https://www.onsemi.com/pdf/datasheet/rb521s30t1-d.pdf"
			(at 328.93 181.61 0)
			(effects
				(font
					(size 1.27 1.27)
					(thickness 0.15)
				)
				(justify left bottom)
				(hide yes)
			)
		)
		(property "Description" "Small Signal Schottky Diode, Single, 30 V, 200 mA, 500 mV, 1 A, 125 °C"
			(at 351.79 194.31 0)
			(effects
				(font
					(size 1.27 1.27)
				)
				(hide yes)
			)
		)
		(property "MPN" "RB521S30T1G"
			(at 349.25 190.5 0)
			(effects
				(font
					(size 1.27 1.27)
					(thickness 0.15)
				)
			)
		)
		(property "Manufacturer" "ON Semiconductor"
			(at 328.93 176.53 0)
			(effects
				(font
					(size 1.27 1.27)
					(thickness 0.15)
				)
				(justify left bottom)
				(hide yes)
			)
		)
		(property "Author" "Antmicro"
			(at 328.93 173.99 0)
			(effects
				(font
					(size 1.27 1.27)
					(thickness 0.15)
				)
				(justify left bottom)
				(hide yes)
			)
		)
		(property "License" "Apache-2.0"
			(at 328.93 171.45 0)
			(effects
				(font
					(size 1.27 1.27)
					(thickness 0.15)
				)
				(justify left bottom)
				(hide yes)
			)
		)
		(pin "1"
		)
		(pin "2"
		)
		(instances
			(project "usb_debug_pd"
				(path ""
					(reference "D?")
					(unit 1)
				)
			)
			(project "jetson-agx-thor-baseboard"
				(path ""
					(reference "D17")
					(unit 1)
				)
			)
		)
	)
	(symbol
		(lib_id "antmicropower:GND")
		(at 276.86 237.49 0)
		(mirror y)
		(unit 1)
		(exclude_from_sim no)
		(in_bom yes)
		(on_board yes)
		(dnp no)
		(property "Reference" "#PWR0231"
			(at 276.86 243.84 0)
			(effects
				(font
					(size 1.27 1.27)
				)
				(justify left bottom)
				(hide yes)
			)
		)
		(property "Value" "GND"
			(at 276.86 241.3 0)
			(effects
				(font
					(size 1.27 1.27)
					(thickness 0.15)
				)
			)
		)
		(property "Footprint" ""
			(at 267.97 245.11 0)
			(effects
				(font
					(size 1.27 1.27)
					(thickness 0.15)
				)
				(justify left bottom)
				(hide yes)
			)
		)
		(property "Datasheet" ""
			(at 267.97 250.19 0)
			(effects
				(font
					(size 1.27 1.27)
					(thickness 0.15)
				)
				(justify left bottom)
				(hide yes)
			)
		)
		(property "Description" ""
			(at 276.86 237.49 0)
			(effects
				(font
					(size 1.27 1.27)
				)
				(hide yes)
			)
		)
		(property "Author" "Antmicro"
			(at 267.97 245.11 0)
			(effects
				(font
					(size 1.27 1.27)
					(thickness 0.15)
				)
				(justify left bottom)
				(hide yes)
			)
		)
		(property "License" "Apache-2.0"
			(at 267.97 247.65 0)
			(effects
				(font
					(size 1.27 1.27)
					(thickness 0.15)
				)
				(justify left bottom)
				(hide yes)
			)
		)
		(pin "1"
		)
		(instances
			(project "usb_debug_pd"
				(path ""
					(reference "#PWR?")
					(unit 1)
				)
			)
			(project "jetson-agx-thor-baseboard"
				(path ""
					(reference "#PWR0231")
					(unit 1)
				)
			)
		)
	)
	(symbol
		(lib_id "antmicroTestPoints:TP_0.75mm_SMD")
		(at 233.68 212.09 0)
		(unit 1)
		(exclude_from_sim no)
		(in_bom no)
		(on_board yes)
		(dnp no)
		(property "Reference" "TP12"
			(at 237.49 212.725 0)
			(effects
				(font
					(size 1.27 1.27)
				)
				(justify left bottom)
			)
		)
		(property "Value" "TP_0.75mm_SMD"
			(at 243.84 215.9 0)
			(effects
				(font
					(size 1.27 1.27)
					(thickness 0.15)
				)
				(justify left bottom)
				(hide yes)
			)
		)
		(property "Footprint" "antmicro-footprints:TP_SMD_0.75mm"
			(at 243.84 218.44 0)
			(effects
				(font
					(size 1.27 1.27)
					(thickness 0.15)
				)
				(justify left bottom)
				(hide yes)
			)
		)
		(property "Datasheet" ""
			(at 251.46 224.79 0)
			(effects
				(font
					(size 1.27 1.27)
					(thickness 0.15)
				)
				(justify left bottom)
				(hide yes)
			)
		)
		(property "Description" "SMT test point"
			(at 233.68 212.09 0)
			(effects
				(font
					(size 1.27 1.27)
				)
				(hide yes)
			)
		)
		(property "MPN" ""
			(at 244.475 223.52 0)
			(effects
				(font
					(size 1.27 1.27)
					(thickness 0.15)
				)
				(justify left bottom)
				(hide yes)
			)
		)
		(property "Manufacturer" ""
			(at 244.475 218.44 0)
			(effects
				(font
					(size 1.27 1.27)
					(thickness 0.15)
				)
				(justify left bottom)
				(hide yes)
			)
		)
		(property "Author" "Antmicro"
			(at 243.84 220.98 0)
			(effects
				(font
					(size 1.27 1.27)
					(thickness 0.15)
				)
				(justify left bottom)
				(hide yes)
			)
		)
		(property "License" "Apache-2.0"
			(at 243.84 223.52 0)
			(effects
				(font
					(size 1.27 1.27)
					(thickness 0.15)
				)
				(justify left bottom)
				(hide yes)
			)
		)
		(pin "1"
		)
		(instances
			(project "usb_debug_pd"
				(path ""
					(reference "TP?")
					(unit 1)
				)
			)
			(project "jetson-agx-thor-baseboard"
				(path ""
					(reference "TP12")
					(unit 1)
				)
			)
		)
	)
	(symbol
		(lib_id "antmicroTVSDiodes:TPD4E05U06QDQARQ1")
		(at 308.61 101.6 270)
		(unit 1)
		(exclude_from_sim no)
		(in_bom yes)
		(on_board yes)
		(dnp no)
		(property "Reference" "U42"
			(at 296.672 111.76 90)
			(effects
				(font
					(size 1.27 1.27)
				)
				(justify left)
			)
		)
		(property "Value" "TPD4E05U06QDQARQ1"
			(at 298.45 125.73 0)
			(effects
				(font
					(size 1.27 1.27)
					(thickness 0.15)
				)
				(justify left bottom)
				(hide yes)
			)
		)
		(property "Footprint" "antmicro-footprints:USON-10_2.5x1mm_P0.5mm"
			(at 303.53 125.73 0)
			(effects
				(font
					(size 1.27 1.27)
					(thickness 0.15)
				)
				(justify left bottom)
				(hide yes)
			)
		)
		(property "Datasheet" "https://www.ti.com/lit/ds/symlink/tpd4e05u06-q1.pdf?HQS=dis-mous-null-mousermode-dsf-pf-null-wwe&ts=1663591265741&ref_url=https%253A%252F%252Fwww.mouser.com%252F"
			(at 300.99 125.73 0)
			(effects
				(font
					(size 1.27 1.27)
					(thickness 0.15)
				)
				(justify left bottom)
				(hide yes)
			)
		)
		(property "Description" "TVS diode array, 12 kV, USON-10, 5.5 V, 0.5 pF"
			(at 308.61 101.6 0)
			(effects
				(font
					(size 1.27 1.27)
				)
				(hide yes)
			)
		)
		(property "Manufacturer" "Texas Instruments"
			(at 295.91 125.73 0)
			(effects
				(font
					(size 1.27 1.27)
					(thickness 0.15)
				)
				(justify left bottom)
				(hide yes)
			)
		)
		(property "MPN" "TPD4E05U06QDQARQ1"
			(at 296.672 114.046 90)
			(effects
				(font
					(size 1.27 1.27)
					(thickness 0.15)
				)
				(justify left)
			)
		)
		(property "Author" "Antmicro"
			(at 293.37 125.73 0)
			(effects
				(font
					(size 1.27 1.27)
					(thickness 0.15)
				)
				(justify left bottom)
				(hide yes)
			)
		)
		(property "License" "Apache-2.0"
			(at 290.83 125.73 0)
			(effects
				(font
					(size 1.27 1.27)
					(thickness 0.15)
				)
				(justify left bottom)
				(hide yes)
			)
		)
		(pin "1"
		)
		(pin "10"
		)
		(pin "2"
		)
		(pin "3"
		)
		(pin "4"
		)
		(pin "5"
		)
		(pin "6"
		)
		(pin "7"
		)
		(pin "8"
		)
		(pin "9"
		)
		(instances
			(project "usb_debug_pd"
				(path ""
					(reference "U?")
					(unit 1)
				)
			)
			(project "jetson-agx-thor-baseboard"
				(path ""
					(reference "U42")
					(unit 1)
				)
			)
		)
	)
	(symbol
		(lib_id "antmicropower:GND")
		(at 97.79 140.97 0)
		(unit 1)
		(exclude_from_sim no)
		(in_bom yes)
		(on_board yes)
		(dnp no)
		(property "Reference" "#PWR0237"
			(at 97.79 147.32 0)
			(effects
				(font
					(size 1.27 1.27)
				)
				(justify left bottom)
				(hide yes)
			)
		)
		(property "Value" "GND"
			(at 97.79 144.78 0)
			(effects
				(font
					(size 1.27 1.27)
					(thickness 0.15)
				)
			)
		)
		(property "Footprint" ""
			(at 106.68 148.59 0)
			(effects
				(font
					(size 1.27 1.27)
					(thickness 0.15)
				)
				(justify left bottom)
				(hide yes)
			)
		)
		(property "Datasheet" ""
			(at 106.68 153.67 0)
			(effects
				(font
					(size 1.27 1.27)
					(thickness 0.15)
				)
				(justify left bottom)
				(hide yes)
			)
		)
		(property "Description" ""
			(at 97.79 140.97 0)
			(effects
				(font
					(size 1.27 1.27)
				)
				(hide yes)
			)
		)
		(property "Author" "Antmicro"
			(at 106.68 148.59 0)
			(effects
				(font
					(size 1.27 1.27)
					(thickness 0.15)
				)
				(justify left bottom)
				(hide yes)
			)
		)
		(property "License" "Apache-2.0"
			(at 106.68 151.13 0)
			(effects
				(font
					(size 1.27 1.27)
					(thickness 0.15)
				)
				(justify left bottom)
				(hide yes)
			)
		)
		(pin "1"
		)
		(instances
			(project "usb_debug_pd"
				(path ""
					(reference "#PWR?")
					(unit 1)
				)
			)
			(project "jetson-agx-thor-baseboard"
				(path ""
					(reference "#PWR0237")
					(unit 1)
				)
			)
		)
	)
	(symbol
		(lib_id "antmicroResistors0402:R_4k7_0402")
		(at 245.11 222.25 270)
		(unit 1)
		(exclude_from_sim no)
		(in_bom yes)
		(on_board yes)
		(dnp no)
		(property "Reference" "R107"
			(at 244.602 222.758 0)
			(effects
				(font
					(size 1.27 1.27)
				)
				(justify right top)
			)
		)
		(property "Value" "R_4k7_0402"
			(at 232.41 242.57 0)
			(effects
				(font
					(size 1.27 1.27)
					(thickness 0.15)
				)
				(justify left bottom)
				(hide yes)
			)
		)
		(property "Footprint" "antmicro-footprints:R_0402_1005Metric"
			(at 229.87 242.57 0)
			(effects
				(font
					(size 1.27 1.27)
					(thickness 0.15)
				)
				(justify left bottom)
				(hide yes)
			)
		)
		(property "Datasheet" "https://www.bourns.com/docs/product-datasheets/cr.pdf"
			(at 227.33 242.57 0)
			(effects
				(font
					(size 1.27 1.27)
					(thickness 0.15)
				)
				(justify left bottom)
				(hide yes)
			)
		)
		(property "Description" "SMD Chip Resistor, 4.7 kohm, ± 1%, 62.5 mW, 0402 [1005 Metric], Thick Film, General Purpose"
			(at 245.11 222.25 0)
			(effects
				(font
					(size 1.27 1.27)
				)
				(hide yes)
			)
		)
		(property "Manufacturer" "Bourns"
			(at 222.25 242.57 0)
			(effects
				(font
					(size 1.27 1.27)
					(thickness 0.15)
				)
				(justify left bottom)
				(hide yes)
			)
		)
		(property "MPN" "CR0402-FX-4701GLF"
			(at 224.79 242.57 0)
			(effects
				(font
					(size 1.27 1.27)
					(thickness 0.15)
				)
				(justify left bottom)
				(hide yes)
			)
		)
		(property "Val" "4k7"
			(at 244.475 231.14 0)
			(effects
				(font
					(size 1.27 1.27)
					(thickness 0.15)
				)
				(justify right top)
			)
		)
		(property "License" "Apache-2.0"
			(at 219.71 242.57 0)
			(effects
				(font
					(size 1.27 1.27)
					(thickness 0.15)
				)
				(justify left bottom)
				(hide yes)
			)
		)
		(property "Author" "Antmicro"
			(at 217.17 242.57 0)
			(effects
				(font
					(size 1.27 1.27)
					(thickness 0.15)
				)
				(justify left bottom)
				(hide yes)
			)
		)
		(property "Tolerance" "1%"
			(at 234.95 242.57 0)
			(effects
				(font
					(size 1.27 1.27)
				)
				(justify left bottom)
				(hide yes)
			)
		)
		(pin "1"
		)
		(pin "2"
		)
		(instances
			(project "usb_debug_pd"
				(path ""
					(reference "R?")
					(unit 1)
				)
			)
			(project "jetson-agx-thor-baseboard"
				(path ""
					(reference "R107")
					(unit 1)
				)
			)
		)
	)
	(symbol
		(lib_id "antmicropower:+3V3")
		(at 138.43 182.88 0)
		(unit 1)
		(exclude_from_sim no)
		(in_bom yes)
		(on_board yes)
		(dnp no)
		(property "Reference" "#PWR0213"
			(at 138.43 186.69 0)
			(effects
				(font
					(size 1.27 1.27)
				)
				(justify left bottom)
				(hide yes)
			)
		)
		(property "Value" "+3V3"
			(at 135.255 179.07 0)
			(effects
				(font
					(size 1.27 1.27)
					(thickness 0.15)
				)
				(justify left)
			)
		)
		(property "Footprint" ""
			(at 153.67 190.5 0)
			(effects
				(font
					(size 1.27 1.27)
					(thickness 0.15)
				)
				(justify left bottom)
				(hide yes)
			)
		)
		(property "Datasheet" ""
			(at 153.67 193.04 0)
			(effects
				(font
					(size 1.27 1.27)
					(thickness 0.15)
				)
				(justify left bottom)
				(hide yes)
			)
		)
		(property "Description" ""
			(at 138.43 182.88 0)
			(effects
				(font
					(size 1.27 1.27)
				)
				(hide yes)
			)
		)
		(property "Author" "Antmicro"
			(at 153.67 185.42 0)
			(effects
				(font
					(size 1.27 1.27)
					(thickness 0.15)
				)
				(justify left bottom)
				(hide yes)
			)
		)
		(property "License" "Apache-2.0"
			(at 153.67 187.96 0)
			(effects
				(font
					(size 1.27 1.27)
					(thickness 0.15)
				)
				(justify left bottom)
				(hide yes)
			)
		)
		(pin "1"
		)
		(instances
			(project "usb_debug_pd"
				(path ""
					(reference "#PWR?")
					(unit 1)
				)
			)
			(project "jetson-agx-thor-baseboard"
				(path ""
					(reference "#PWR0213")
					(unit 1)
				)
			)
		)
	)
	(symbol
		(lib_id "antmicroTestPoints:TP_0.75mm_SMD")
		(at 251.46 260.35 0)
		(unit 1)
		(exclude_from_sim no)
		(in_bom no)
		(on_board yes)
		(dnp no)
		(property "Reference" "TP15"
			(at 255.27 260.985 0)
			(effects
				(font
					(size 1.27 1.27)
				)
				(justify left bottom)
			)
		)
		(property "Value" "TP_0.75mm_SMD"
			(at 261.62 264.16 0)
			(effects
				(font
					(size 1.27 1.27)
					(thickness 0.15)
				)
				(justify left bottom)
				(hide yes)
			)
		)
		(property "Footprint" "antmicro-footprints:TP_SMD_0.75mm"
			(at 261.62 266.7 0)
			(effects
				(font
					(size 1.27 1.27)
					(thickness 0.15)
				)
				(justify left bottom)
				(hide yes)
			)
		)
		(property "Datasheet" ""
			(at 269.24 273.05 0)
			(effects
				(font
					(size 1.27 1.27)
					(thickness 0.15)
				)
				(justify left bottom)
				(hide yes)
			)
		)
		(property "Description" "SMT test point"
			(at 251.46 260.35 0)
			(effects
				(font
					(size 1.27 1.27)
				)
				(hide yes)
			)
		)
		(property "MPN" ""
			(at 262.255 271.78 0)
			(effects
				(font
					(size 1.27 1.27)
					(thickness 0.15)
				)
				(justify left bottom)
				(hide yes)
			)
		)
		(property "Manufacturer" ""
			(at 262.255 266.7 0)
			(effects
				(font
					(size 1.27 1.27)
					(thickness 0.15)
				)
				(justify left bottom)
				(hide yes)
			)
		)
		(property "Author" "Antmicro"
			(at 261.62 269.24 0)
			(effects
				(font
					(size 1.27 1.27)
					(thickness 0.15)
				)
				(justify left bottom)
				(hide yes)
			)
		)
		(property "License" "Apache-2.0"
			(at 261.62 271.78 0)
			(effects
				(font
					(size 1.27 1.27)
					(thickness 0.15)
				)
				(justify left bottom)
				(hide yes)
			)
		)
		(pin "1"
		)
		(instances
			(project "usb_debug_pd"
				(path ""
					(reference "TP?")
					(unit 1)
				)
			)
			(project "jetson-agx-thor-baseboard"
				(path ""
					(reference "TP15")
					(unit 1)
				)
			)
		)
	)
	(symbol
		(lib_id "antmicroResistors0402:R_200R_0402")
		(at 255.27 231.14 0)
		(unit 1)
		(exclude_from_sim no)
		(in_bom yes)
		(on_board yes)
		(dnp no)
		(property "Reference" "R108"
			(at 260.35 230.505 0)
			(effects
				(font
					(size 1.27 1.27)
				)
				(justify left bottom)
			)
		)
		(property "Value" "R_200R_0402"
			(at 275.59 243.84 0)
			(effects
				(font
					(size 1.27 1.27)
					(thickness 0.15)
				)
				(justify left bottom)
				(hide yes)
			)
		)
		(property "Footprint" "antmicro-footprints:R_0402_1005Metric"
			(at 275.59 246.38 0)
			(effects
				(font
					(size 1.27 1.27)
					(thickness 0.15)
				)
				(justify left bottom)
				(hide yes)
			)
		)
		(property "Datasheet" "https://www.bourns.com/docs/product-datasheets/cr.pdf"
			(at 275.59 248.92 0)
			(effects
				(font
					(size 1.27 1.27)
					(thickness 0.15)
				)
				(justify left bottom)
				(hide yes)
			)
		)
		(property "Description" "SMD Chip Resistor, 200 ohm, ± 1%, 62.5 mW, 0402 [1005 Metric], Thick Film, General Purpose"
			(at 255.27 231.14 0)
			(effects
				(font
					(size 1.27 1.27)
				)
				(hide yes)
			)
		)
		(property "Manufacturer" "Bourns"
			(at 275.59 254 0)
			(effects
				(font
					(size 1.27 1.27)
					(thickness 0.15)
				)
				(justify left bottom)
				(hide yes)
			)
		)
		(property "MPN" "CR0402-FX-2000GLF"
			(at 275.59 251.46 0)
			(effects
				(font
					(size 1.27 1.27)
					(thickness 0.15)
				)
				(justify left bottom)
				(hide yes)
			)
		)
		(property "Val" "200R"
			(at 250.19 230.505 0)
			(effects
				(font
					(size 1.27 1.27)
					(thickness 0.15)
				)
				(justify left bottom)
			)
		)
		(property "License" "Apache-2.0"
			(at 275.59 256.54 0)
			(effects
				(font
					(size 1.27 1.27)
					(thickness 0.15)
				)
				(justify left bottom)
				(hide yes)
			)
		)
		(property "Author" "Antmicro"
			(at 275.59 259.08 0)
			(effects
				(font
					(size 1.27 1.27)
					(thickness 0.15)
				)
				(justify left bottom)
				(hide yes)
			)
		)
		(property "Tolerance" "1%"
			(at 275.59 241.3 0)
			(effects
				(font
					(size 1.27 1.27)
				)
				(justify left bottom)
				(hide yes)
			)
		)
		(pin "1"
		)
		(pin "2"
		)
		(instances
			(project "usb_debug_pd"
				(path ""
					(reference "R?")
					(unit 1)
				)
			)
			(project "jetson-agx-thor-baseboard"
				(path ""
					(reference "R108")
					(unit 1)
				)
			)
		)
	)
	(symbol
		(lib_id "antmicroCapacitors0402:C_100n_0402")
		(at 74.93 100.33 270)
		(unit 1)
		(exclude_from_sim no)
		(in_bom yes)
		(on_board yes)
		(dnp no)
		(fields_autoplaced yes)
		(property "Reference" "C234"
			(at 77.47 101.6063 90)
			(effects
				(font
					(size 1.27 1.27)
				)
				(justify left)
			)
		)
		(property "Value" "C_100n_0402"
			(at 64.77 120.65 0)
			(effects
				(font
					(size 1.27 1.27)
					(thickness 0.15)
				)
				(justify left bottom)
				(hide yes)
			)
		)
		(property "Footprint" "antmicro-footprints:C_0402_1005Metric"
			(at 62.23 120.65 0)
			(effects
				(font
					(size 1.27 1.27)
					(thickness 0.15)
				)
				(justify left bottom)
				(hide yes)
			)
		)
		(property "Datasheet" "https://www.murata.com/products/productdetail?partno=GRM155R61H104KE14%23"
			(at 59.69 120.65 0)
			(effects
				(font
					(size 1.27 1.27)
					(thickness 0.15)
				)
				(justify left bottom)
				(hide yes)
			)
		)
		(property "Description" "SMD Multilayer Ceramic Capacitor, 0.1 µF, 50 V, 0402 [1005 Metric], ± 10%, X5R, GRM Series"
			(at 74.93 100.33 0)
			(effects
				(font
					(size 1.27 1.27)
				)
				(hide yes)
			)
		)
		(property "MPN" "GRM155R61H104KE14D"
			(at 57.15 120.65 0)
			(effects
				(font
					(size 1.27 1.27)
					(thickness 0.15)
				)
				(justify left bottom)
				(hide yes)
			)
		)
		(property "Manufacturer" "Murata"
			(at 54.61 120.65 0)
			(effects
				(font
					(size 1.27 1.27)
					(thickness 0.15)
				)
				(justify left bottom)
				(hide yes)
			)
		)
		(property "Val" "100n"
			(at 77.47 104.1463 90)
			(effects
				(font
					(size 1.27 1.27)
					(thickness 0.15)
				)
				(justify left)
			)
		)
		(property "License" "Apache-2.0"
			(at 52.07 120.65 0)
			(effects
				(font
					(size 1.27 1.27)
					(thickness 0.15)
				)
				(justify left bottom)
				(hide yes)
			)
		)
		(property "Author" "Antmicro"
			(at 49.53 120.65 0)
			(effects
				(font
					(size 1.27 1.27)
					(thickness 0.15)
				)
				(justify left bottom)
				(hide yes)
			)
		)
		(property "Voltage" "50V"
			(at 46.99 120.65 0)
			(effects
				(font
					(size 1.27 1.27)
				)
				(justify left bottom)
				(hide yes)
			)
		)
		(property "Dielectric" "X5R"
			(at 44.45 120.65 0)
			(effects
				(font
					(size 1.27 1.27)
				)
				(justify left bottom)
				(hide yes)
			)
		)
		(pin "1"
		)
		(pin "2"
		)
		(instances
			(project "usb_debug_pd"
				(path ""
					(reference "C?")
					(unit 1)
				)
			)
			(project "jetson-agx-thor-baseboard"
				(path ""
					(reference "C234")
					(unit 1)
				)
			)
		)
	)
	(symbol
		(lib_id "antmicroPMICVoltageRegulatorsLinear:NCP718BSN330T1G")
		(at 87.63 64.77 0)
		(unit 1)
		(exclude_from_sim no)
		(in_bom yes)
		(on_board yes)
		(dnp no)
		(property "Reference" "U32"
			(at 98.298 57.15 0)
			(effects
				(font
					(size 1.27 1.27)
					(thickness 0.15)
				)
			)
		)
		(property "Value" "NCP718BSN330T1G"
			(at 118.11 69.85 0)
			(effects
				(font
					(size 1.27 1.27)
					(thickness 0.15)
				)
				(justify left bottom)
				(hide yes)
			)
		)
		(property "Footprint" "antmicro-footprints:SOT-23-5"
			(at 118.11 72.39 0)
			(effects
				(font
					(size 1.27 1.27)
					(thickness 0.15)
				)
				(justify left bottom)
				(hide yes)
			)
		)
		(property "Datasheet" "https://www.mouser.com/datasheet/2/308/NCP718_D-1224359.pdf"
			(at 118.11 74.93 0)
			(effects
				(font
					(size 1.27 1.27)
					(thickness 0.15)
				)
				(justify left bottom)
				(hide yes)
			)
		)
		(property "Description" "Linear Voltage Regulator IC Positive Fixed 1 Output 300mA TSOT-23-5"
			(at 87.63 64.77 0)
			(effects
				(font
					(size 1.27 1.27)
				)
				(hide yes)
			)
		)
		(property "MPN" "NCP718BSN330T1G"
			(at 98.298 59.69 0)
			(effects
				(font
					(size 1.27 1.27)
					(thickness 0.15)
				)
			)
		)
		(property "Manufacturer" "ON Semiconductor"
			(at 118.11 80.01 0)
			(effects
				(font
					(size 1.27 1.27)
					(thickness 0.15)
				)
				(justify left bottom)
				(hide yes)
			)
		)
		(property "Author" "Antmicro"
			(at 118.11 82.55 0)
			(effects
				(font
					(size 1.27 1.27)
					(thickness 0.15)
				)
				(justify left bottom)
				(hide yes)
			)
		)
		(property "License" "Apache-2.0"
			(at 118.11 85.09 0)
			(effects
				(font
					(size 1.27 1.27)
					(thickness 0.15)
				)
				(justify left bottom)
				(hide yes)
			)
		)
		(pin "3"
		)
		(pin "4"
		)
		(pin "1"
		)
		(pin "5"
		)
		(pin "2"
		)
		(instances
			(project "usb_debug_pd"
				(path ""
					(reference "U?")
					(unit 1)
				)
			)
			(project ""
				(path ""
					(reference "U32")
					(unit 1)
				)
			)
		)
	)
	(symbol
		(lib_id "antmicroResistors0402:R_0R_0402")
		(at 55.88 254 0)
		(unit 1)
		(exclude_from_sim no)
		(in_bom no)
		(on_board yes)
		(dnp yes)
		(property "Reference" "R100"
			(at 62.992 252.73 0)
			(effects
				(font
					(size 1.27 1.27)
					(thickness 0.15)
				)
			)
		)
		(property "Value" "R_0R_0402"
			(at 76.2 266.7 0)
			(effects
				(font
					(size 1.27 1.27)
					(thickness 0.15)
				)
				(justify left bottom)
				(hide yes)
			)
		)
		(property "Footprint" "antmicro-footprints:R_0402_1005Metric"
			(at 76.2 269.24 0)
			(effects
				(font
					(size 1.27 1.27)
					(thickness 0.15)
				)
				(justify left bottom)
				(hide yes)
			)
		)
		(property "Datasheet" "https://industrial.panasonic.com/cdbs/www-data/pdf/RDA0000/AOA0000C301.pdf"
			(at 76.2 271.78 0)
			(effects
				(font
					(size 1.27 1.27)
					(thickness 0.15)
				)
				(justify left bottom)
				(hide yes)
			)
		)
		(property "Description" "SMD Chip Resistor, Jumper, 0 ohm, 100 mW, 0402 [1005 Metric], Thick Film, General Purpose"
			(at 76.2 287.02 0)
			(effects
				(font
					(size 1.27 1.27)
				)
				(justify left bottom)
				(hide yes)
			)
		)
		(property "MPN" "ERJ2GE0R00X"
			(at 76.2 274.32 0)
			(effects
				(font
					(size 1.27 1.27)
					(thickness 0.15)
				)
				(justify left bottom)
				(hide yes)
			)
		)
		(property "Manufacturer" "Panasonic"
			(at 76.2 276.86 0)
			(effects
				(font
					(size 1.27 1.27)
					(thickness 0.15)
				)
				(justify left bottom)
				(hide yes)
			)
		)
		(property "License" "Apache-2.0"
			(at 76.2 279.4 0)
			(effects
				(font
					(size 1.27 1.27)
					(thickness 0.15)
				)
				(justify left bottom)
				(hide yes)
			)
		)
		(property "Author" "Antmicro"
			(at 76.2 281.94 0)
			(effects
				(font
					(size 1.27 1.27)
					(thickness 0.15)
				)
				(justify left bottom)
				(hide yes)
			)
		)
		(property "Val" "0R"
			(at 55.118 252.73 0)
			(effects
				(font
					(size 1.27 1.27)
					(thickness 0.15)
				)
			)
		)
		(property "Tolerance" "~"
			(at 76.2 264.16 0)
			(effects
				(font
					(size 1.27 1.27)
				)
				(justify left bottom)
				(hide yes)
			)
		)
		(property "Current" "1A"
			(at 76.2 284.48 0)
			(effects
				(font
					(size 1.27 1.27)
					(thickness 0.15)
				)
				(justify left bottom)
				(hide yes)
			)
		)
		(pin "2"
		)
		(pin "1"
		)
		(instances
			(project "jetson-agx-thor-baseboard"
				(path ""
					(reference "R100")
					(unit 1)
				)
			)
		)
	)
	(symbol
		(lib_id "antmicroResistors0402:R_10M_0402")
		(at 78.74 143.51 90)
		(unit 1)
		(exclude_from_sim no)
		(in_bom no)
		(on_board yes)
		(dnp yes)
		(property "Reference" "R286"
			(at 76.2 139.7 90)
			(effects
				(font
					(size 1.27 1.27)
					(thickness 0.15)
				)
				(justify left)
			)
		)
		(property "Value" "R_10M_0402"
			(at 91.44 123.19 0)
			(effects
				(font
					(size 1.27 1.27)
					(thickness 0.15)
				)
				(justify left bottom)
				(hide yes)
			)
		)
		(property "Footprint" "antmicro-footprints:R_0402_1005Metric"
			(at 93.98 123.19 0)
			(effects
				(font
					(size 1.27 1.27)
					(thickness 0.15)
				)
				(justify left bottom)
				(hide yes)
			)
		)
		(property "Datasheet" "https://www.bourns.com/docs/product-datasheets/cr.pdf"
			(at 96.52 123.19 0)
			(effects
				(font
					(size 1.27 1.27)
					(thickness 0.15)
				)
				(justify left bottom)
				(hide yes)
			)
		)
		(property "Description" "SMD Chip Resistor"
			(at 78.74 143.51 0)
			(effects
				(font
					(size 1.27 1.27)
				)
				(hide yes)
			)
		)
		(property "MPN" "CR0402-FX-1005GLF"
			(at 99.06 123.19 0)
			(effects
				(font
					(size 1.27 1.27)
					(thickness 0.15)
				)
				(justify left bottom)
				(hide yes)
			)
		)
		(property "Manufacturer" "Bourns"
			(at 101.6 123.19 0)
			(effects
				(font
					(size 1.27 1.27)
					(thickness 0.15)
				)
				(justify left bottom)
				(hide yes)
			)
		)
		(property "License" "Apache-2.0"
			(at 104.14 123.19 0)
			(effects
				(font
					(size 1.27 1.27)
					(thickness 0.15)
				)
				(justify left bottom)
				(hide yes)
			)
		)
		(property "Author" "Antmicro"
			(at 106.68 123.19 0)
			(effects
				(font
					(size 1.27 1.27)
					(thickness 0.15)
				)
				(justify left bottom)
				(hide yes)
			)
		)
		(property "Val" "10M"
			(at 76.2 142.24 90)
			(effects
				(font
					(size 1.27 1.27)
					(thickness 0.15)
				)
				(justify left)
			)
		)
		(property "Tolerance" "1%"
			(at 88.9 123.19 0)
			(effects
				(font
					(size 1.27 1.27)
				)
				(justify left bottom)
				(hide yes)
			)
		)
		(pin "1"
		)
		(pin "2"
		)
		(instances
			(project "usb_debug_pd"
				(path ""
					(reference "R?")
					(unit 1)
				)
			)
			(project "jetson-agx-thor-baseboard"
				(path ""
					(reference "R286")
					(unit 1)
				)
			)
		)
	)
	(symbol
		(lib_id "antmicroResistors0402:R_0R_0402")
		(at 55.88 240.03 0)
		(unit 1)
		(exclude_from_sim no)
		(in_bom no)
		(on_board yes)
		(dnp yes)
		(property "Reference" "R386"
			(at 62.992 238.76 0)
			(effects
				(font
					(size 1.27 1.27)
					(thickness 0.15)
				)
			)
		)
		(property "Value" "R_0R_0402"
			(at 76.2 252.73 0)
			(effects
				(font
					(size 1.27 1.27)
					(thickness 0.15)
				)
				(justify left bottom)
				(hide yes)
			)
		)
		(property "Footprint" "antmicro-footprints:R_0402_1005Metric"
			(at 76.2 255.27 0)
			(effects
				(font
					(size 1.27 1.27)
					(thickness 0.15)
				)
				(justify left bottom)
				(hide yes)
			)
		)
		(property "Datasheet" "https://industrial.panasonic.com/cdbs/www-data/pdf/RDA0000/AOA0000C301.pdf"
			(at 76.2 257.81 0)
			(effects
				(font
					(size 1.27 1.27)
					(thickness 0.15)
				)
				(justify left bottom)
				(hide yes)
			)
		)
		(property "Description" "SMD Chip Resistor, Jumper, 0 ohm, 100 mW, 0402 [1005 Metric], Thick Film, General Purpose"
			(at 76.2 273.05 0)
			(effects
				(font
					(size 1.27 1.27)
				)
				(justify left bottom)
				(hide yes)
			)
		)
		(property "MPN" "ERJ2GE0R00X"
			(at 76.2 260.35 0)
			(effects
				(font
					(size 1.27 1.27)
					(thickness 0.15)
				)
				(justify left bottom)
				(hide yes)
			)
		)
		(property "Manufacturer" "Panasonic"
			(at 76.2 262.89 0)
			(effects
				(font
					(size 1.27 1.27)
					(thickness 0.15)
				)
				(justify left bottom)
				(hide yes)
			)
		)
		(property "License" "Apache-2.0"
			(at 76.2 265.43 0)
			(effects
				(font
					(size 1.27 1.27)
					(thickness 0.15)
				)
				(justify left bottom)
				(hide yes)
			)
		)
		(property "Author" "Antmicro"
			(at 76.2 267.97 0)
			(effects
				(font
					(size 1.27 1.27)
					(thickness 0.15)
				)
				(justify left bottom)
				(hide yes)
			)
		)
		(property "Val" "0R"
			(at 55.118 238.76 0)
			(effects
				(font
					(size 1.27 1.27)
					(thickness 0.15)
				)
			)
		)
		(property "Tolerance" "~"
			(at 76.2 250.19 0)
			(effects
				(font
					(size 1.27 1.27)
				)
				(justify left bottom)
				(hide yes)
			)
		)
		(property "Current" "1A"
			(at 76.2 270.51 0)
			(effects
				(font
					(size 1.27 1.27)
					(thickness 0.15)
				)
				(justify left bottom)
				(hide yes)
			)
		)
		(pin "2"
		)
		(pin "1"
		)
		(instances
			(project "jetson-agx-thor-baseboard"
				(path ""
					(reference "R386")
					(unit 1)
				)
			)
		)
	)
	(symbol
		(lib_id "antmicropower:GND")
		(at 73.66 219.71 0)
		(unit 1)
		(exclude_from_sim no)
		(in_bom yes)
		(on_board yes)
		(dnp no)
		(property "Reference" "#PWR0225"
			(at 73.66 226.06 0)
			(effects
				(font
					(size 1.27 1.27)
				)
				(justify left bottom)
				(hide yes)
			)
		)
		(property "Value" "GND"
			(at 70.104 221.488 0)
			(effects
				(font
					(size 1.27 1.27)
					(thickness 0.15)
				)
			)
		)
		(property "Footprint" ""
			(at 82.55 227.33 0)
			(effects
				(font
					(size 1.27 1.27)
					(thickness 0.15)
				)
				(justify left bottom)
				(hide yes)
			)
		)
		(property "Datasheet" ""
			(at 82.55 232.41 0)
			(effects
				(font
					(size 1.27 1.27)
					(thickness 0.15)
				)
				(justify left bottom)
				(hide yes)
			)
		)
		(property "Description" ""
			(at 73.66 219.71 0)
			(effects
				(font
					(size 1.27 1.27)
				)
				(hide yes)
			)
		)
		(property "Author" "Antmicro"
			(at 82.55 227.33 0)
			(effects
				(font
					(size 1.27 1.27)
					(thickness 0.15)
				)
				(justify left bottom)
				(hide yes)
			)
		)
		(property "License" "Apache-2.0"
			(at 82.55 229.87 0)
			(effects
				(font
					(size 1.27 1.27)
					(thickness 0.15)
				)
				(justify left bottom)
				(hide yes)
			)
		)
		(pin "1"
		)
		(instances
			(project "usb_debug_pd"
				(path ""
					(reference "#PWR?")
					(unit 1)
				)
			)
			(project "jetson-agx-thor-baseboard"
				(path ""
					(reference "#PWR0225")
					(unit 1)
				)
			)
		)
	)
	(symbol
		(lib_id "antmicroInterfaceControllers:TPS65988DHRSHR")
		(at 181.61 193.04 0)
		(unit 1)
		(exclude_from_sim no)
		(in_bom yes)
		(on_board yes)
		(dnp no)
		(fields_autoplaced yes)
		(property "Reference" "U30"
			(at 199.39 185.42 0)
			(effects
				(font
					(size 1.27 1.27)
				)
			)
		)
		(property "Value" "TPS65988DHRSHR"
			(at 231.14 198.12 0)
			(effects
				(font
					(size 1.27 1.27)
					(thickness 0.15)
				)
				(justify left bottom)
				(hide yes)
			)
		)
		(property "Footprint" "antmicro-footprints:IC_TPS65987DDHRSHR"
			(at 231.14 200.66 0)
			(effects
				(font
					(size 1.27 1.27)
					(thickness 0.15)
				)
				(justify left bottom)
				(hide yes)
			)
		)
		(property "Datasheet" "https://www.ti.com/lit/ds/symlink/tps65988.pdf?ts=1662726631004&ref_url=https%253A%252F%252Fwww.ti.com%252Fproduct%252FTPS65988"
			(at 231.14 203.2 0)
			(effects
				(font
					(size 1.27 1.27)
					(thickness 0.15)
				)
				(justify left bottom)
				(hide yes)
			)
		)
		(property "Description" "USB, Type-C Controller PMIC 56-VQFN (7x7)"
			(at 181.61 193.04 0)
			(effects
				(font
					(size 1.27 1.27)
				)
				(hide yes)
			)
		)
		(property "MPN" "TPS65988DHRSHR "
			(at 199.39 187.96 0)
			(effects
				(font
					(size 1.27 1.27)
					(thickness 0.15)
				)
			)
		)
		(property "Manufacturer" "Texas Instruments"
			(at 231.14 208.28 0)
			(effects
				(font
					(size 1.27 1.27)
					(thickness 0.15)
				)
				(justify left bottom)
				(hide yes)
			)
		)
		(property "License" "Apache-2.0"
			(at 231.14 210.82 0)
			(effects
				(font
					(size 1.27 1.27)
					(thickness 0.15)
				)
				(justify left bottom)
				(hide yes)
			)
		)
		(property "Author" "Antmicro"
			(at 231.14 213.36 0)
			(effects
				(font
					(size 1.27 1.27)
					(thickness 0.15)
				)
				(justify left bottom)
				(hide yes)
			)
		)
		(pin "10"
		)
		(pin "16"
		)
		(pin "17"
		)
		(pin "18"
		)
		(pin "20"
		)
		(pin "21"
		)
		(pin "22"
		)
		(pin "23"
		)
		(pin "27"
		)
		(pin "28"
		)
		(pin "29"
		)
		(pin "30"
		)
		(pin "31"
		)
		(pin "32"
		)
		(pin "33"
		)
		(pin "34"
		)
		(pin "35"
		)
		(pin "36"
		)
		(pin "37"
		)
		(pin "38"
		)
		(pin "39"
		)
		(pin "40"
		)
		(pin "41"
		)
		(pin "42"
		)
		(pin "43"
		)
		(pin "44"
		)
		(pin "48"
		)
		(pin "49"
		)
		(pin "5"
		)
		(pin "51"
		)
		(pin "59"
		)
		(pin "6"
		)
		(pin "9"
		)
		(pin "11"
		)
		(pin "13"
		)
		(pin "15"
		)
		(pin "19"
		)
		(pin "24"
		)
		(pin "25"
		)
		(pin "26"
		)
		(pin "50"
		)
		(pin "53"
		)
		(pin "58"
		)
		(pin "8"
		)
		(pin "1"
		)
		(pin "3"
		)
		(pin "45"
		)
		(pin "46"
		)
		(pin "47"
		)
		(pin "52"
		)
		(pin "54"
		)
		(pin "55"
		)
		(pin "56"
		)
		(pin "57"
		)
		(pin "7"
		)
		(instances
			(project "usb_debug_pd"
				(path ""
					(reference "U?")
					(unit 1)
				)
			)
			(project "jetson-agx-thor-baseboard"
				(path ""
					(reference "U30")
					(unit 1)
				)
			)
		)
	)
	(symbol
		(lib_id "antmicropower:GND")
		(at 162.56 72.39 0)
		(unit 1)
		(exclude_from_sim no)
		(in_bom yes)
		(on_board yes)
		(dnp no)
		(property "Reference" "#PWR0128"
			(at 162.56 78.74 0)
			(effects
				(font
					(size 1.27 1.27)
				)
				(justify left bottom)
				(hide yes)
			)
		)
		(property "Value" "GND"
			(at 162.56 76.2 0)
			(effects
				(font
					(size 1.27 1.27)
					(thickness 0.15)
				)
			)
		)
		(property "Footprint" ""
			(at 171.45 80.01 0)
			(effects
				(font
					(size 1.27 1.27)
					(thickness 0.15)
				)
				(justify left bottom)
				(hide yes)
			)
		)
		(property "Datasheet" ""
			(at 171.45 85.09 0)
			(effects
				(font
					(size 1.27 1.27)
					(thickness 0.15)
				)
				(justify left bottom)
				(hide yes)
			)
		)
		(property "Description" ""
			(at 162.56 72.39 0)
			(effects
				(font
					(size 1.27 1.27)
				)
				(hide yes)
			)
		)
		(property "Author" "Antmicro"
			(at 171.45 80.01 0)
			(effects
				(font
					(size 1.27 1.27)
					(thickness 0.15)
				)
				(justify left bottom)
				(hide yes)
			)
		)
		(property "License" "Apache-2.0"
			(at 171.45 82.55 0)
			(effects
				(font
					(size 1.27 1.27)
					(thickness 0.15)
				)
				(justify left bottom)
				(hide yes)
			)
		)
		(pin "1"
		)
		(instances
			(project "jetson-agx-thor-baseboard"
				(path ""
					(reference "#PWR0128")
					(unit 1)
				)
			)
		)
	)
	(symbol
		(lib_id "antmicroLogicTranslatorsLevelShifters:NTS0102_XSON")
		(at 71.12 111.76 0)
		(mirror y)
		(unit 1)
		(exclude_from_sim no)
		(in_bom yes)
		(on_board yes)
		(dnp no)
		(fields_autoplaced yes)
		(property "Reference" "U31"
			(at 60.96 104.14 0)
			(effects
				(font
					(size 1.27 1.27)
					(thickness 0.15)
				)
			)
		)
		(property "Value" "NTS0102_XSON"
			(at 35.56 119.38 0)
			(effects
				(font
					(size 1.27 1.27)
					(thickness 0.15)
				)
				(justify left bottom)
				(hide yes)
			)
		)
		(property "Footprint" "antmicro-footprints:XSON-8_1x1.95mm_P0.5mm"
			(at 35.56 121.92 0)
			(effects
				(font
					(size 1.27 1.27)
					(thickness 0.15)
				)
				(justify left bottom)
				(hide yes)
			)
		)
		(property "Datasheet" "http://www.farnell.com/datasheets/1760723.pdf"
			(at 35.56 124.46 0)
			(effects
				(font
					(size 1.27 1.27)
					(thickness 0.15)
				)
				(justify left bottom)
				(hide yes)
			)
		)
		(property "Description" "Transceiver, 1.65 V to 3.6 V, XSON-8"
			(at 71.12 111.76 0)
			(effects
				(font
					(size 1.27 1.27)
				)
				(hide yes)
			)
		)
		(property "MPN" "NTS0102GT"
			(at 60.96 106.68 0)
			(effects
				(font
					(size 1.27 1.27)
					(thickness 0.15)
				)
			)
		)
		(property "Manufacturer" "NXP"
			(at 35.56 127 0)
			(effects
				(font
					(size 1.27 1.27)
					(thickness 0.15)
				)
				(justify left bottom)
				(hide yes)
			)
		)
		(property "Author" "Antmicro"
			(at 35.56 129.54 0)
			(effects
				(font
					(size 1.27 1.27)
					(thickness 0.15)
				)
				(justify left bottom)
				(hide yes)
			)
		)
		(property "License" "Apache-2.0"
			(at 35.56 132.08 0)
			(effects
				(font
					(size 1.27 1.27)
					(thickness 0.15)
				)
				(justify left bottom)
				(hide yes)
			)
		)
		(pin "2"
		)
		(pin "8"
		)
		(pin "7"
		)
		(pin "4"
		)
		(pin "5"
		)
		(pin "3"
		)
		(pin "6"
		)
		(pin "1"
		)
		(instances
			(project "usb_debug_pd"
				(path ""
					(reference "U?")
					(unit 1)
				)
			)
			(project "jetson-agx-thor-baseboard"
				(path ""
					(reference "U31")
					(unit 1)
				)
			)
		)
	)
	(symbol
		(lib_id "antmicroTestPoints:Tag-Connect_TC2050-IDC-NL_2x5_P1.27mm")
		(at 40.64 204.47 0)
		(unit 1)
		(exclude_from_sim no)
		(in_bom no)
		(on_board yes)
		(dnp no)
		(fields_autoplaced yes)
		(property "Reference" "J4"
			(at 56.515 196.85 0)
			(effects
				(font
					(size 1.27 1.27)
					(thickness 0.15)
				)
			)
		)
		(property "Value" "Tag-Connect_TC2050-IDC-NL_2x5_P1.27mm"
			(at 80.01 208.28 0)
			(effects
				(font
					(size 1.27 1.27)
					(thickness 0.15)
				)
				(justify left bottom)
				(hide yes)
			)
		)
		(property "Footprint" "antmicro-footprints:Tag-Connect_TC2050-IDC-NL_2x5_P1.27mm"
			(at 80.01 210.82 0)
			(effects
				(font
					(size 1.27 1.27)
					(thickness 0.15)
				)
				(justify left bottom)
				(hide yes)
			)
		)
		(property "Datasheet" "https://www.tag-connect.com/wp-content/uploads/bsk-pdf-manager/TC2050-IDC-NL_Datasheet_8.pdf"
			(at 80.01 213.36 0)
			(effects
				(font
					(size 1.27 1.27)
					(thickness 0.15)
				)
				(justify left bottom)
				(hide yes)
			)
		)
		(property "Description" "Tag Connect 2x5 1.27mm terminal"
			(at 80.01 226.06 0)
			(effects
				(font
					(size 1.27 1.27)
				)
				(justify left bottom)
				(hide yes)
			)
		)
		(property "MPN" "TC2050-IDC-NL"
			(at 56.515 199.39 0)
			(effects
				(font
					(size 1.27 1.27)
					(thickness 0.15)
				)
			)
		)
		(property "Manufacturer" "Tag Connect"
			(at 80.01 218.44 0)
			(effects
				(font
					(size 1.27 1.27)
					(thickness 0.15)
				)
				(justify left bottom)
				(hide yes)
			)
		)
		(property "Author" "Antmicro"
			(at 80.01 220.98 0)
			(effects
				(font
					(size 1.27 1.27)
					(thickness 0.15)
				)
				(justify left bottom)
				(hide yes)
			)
		)
		(property "License" "Apache-2.0"
			(at 80.01 223.52 0)
			(effects
				(font
					(size 1.27 1.27)
					(thickness 0.15)
				)
				(justify left bottom)
				(hide yes)
			)
		)
		(pin "4"
		)
		(pin "7"
		)
		(pin "6"
		)
		(pin "10"
		)
		(pin "3"
		)
		(pin "8"
		)
		(pin "2"
		)
		(pin "1"
		)
		(pin "9"
		)
		(pin "5"
		)
		(instances
			(project "usb_debug_pd"
				(path ""
					(reference "J?")
					(unit 1)
				)
			)
			(project "jetson-agx-thor-baseboard"
				(path ""
					(reference "J4")
					(unit 1)
				)
			)
		)
	)
	(symbol
		(lib_id "antmicroLEDIndicationDiscrete:LED_G_0603_LTST-C190GKT")
		(at 271.78 236.22 0)
		(mirror y)
		(unit 1)
		(exclude_from_sim no)
		(in_bom yes)
		(on_board yes)
		(dnp no)
		(property "Reference" "D19"
			(at 271.78 235.585 0)
			(effects
				(font
					(size 1.27 1.27)
				)
				(justify right bottom)
			)
		)
		(property "Value" "LED_G_0603_LTST-C190GKT"
			(at 248.92 243.84 0)
			(effects
				(font
					(size 1.27 1.27)
					(thickness 0.15)
				)
				(justify left bottom)
				(hide yes)
			)
		)
		(property "Footprint" "antmicro-footprints:LED_0603_1608Metric_G"
			(at 248.92 246.38 0)
			(effects
				(font
					(size 1.27 1.27)
					(thickness 0.15)
				)
				(justify left bottom)
				(hide yes)
			)
		)
		(property "Datasheet" "https://media.digikey.com/pdf/Data%20Sheets/Lite-On%20PDFs/LTST-C190GKT.pdf"
			(at 248.92 248.92 0)
			(effects
				(font
					(size 1.27 1.27)
					(thickness 0.15)
				)
				(justify left bottom)
				(hide yes)
			)
		)
		(property "Description" "LED, Green, SMD, 0603, 20 mA, 2.1 V, 569 nm"
			(at 271.78 236.22 0)
			(effects
				(font
					(size 1.27 1.27)
				)
				(hide yes)
			)
		)
		(property "MPN" "LTST-C190GKT"
			(at 248.92 251.46 0)
			(effects
				(font
					(size 1.27 1.27)
					(thickness 0.15)
				)
				(justify left bottom)
				(hide yes)
			)
		)
		(property "Manufacturer" "Lite-On"
			(at 248.92 254 0)
			(effects
				(font
					(size 1.27 1.27)
					(thickness 0.15)
				)
				(justify left bottom)
				(hide yes)
			)
		)
		(property "Author" "Antmicro"
			(at 248.92 256.54 0)
			(effects
				(font
					(size 1.27 1.27)
					(thickness 0.15)
				)
				(justify left bottom)
				(hide yes)
			)
		)
		(property "License" "Apache-2.0"
			(at 248.92 259.08 0)
			(effects
				(font
					(size 1.27 1.27)
					(thickness 0.15)
				)
				(justify left bottom)
				(hide yes)
			)
		)
		(property "Color" "Green"
			(at 266.065 239.395 0)
			(effects
				(font
					(size 1.27 1.27)
				)
				(justify right bottom)
			)
		)
		(pin "1"
		)
		(pin "2"
		)
		(instances
			(project "usb_debug_pd"
				(path ""
					(reference "D?")
					(unit 1)
				)
			)
			(project "jetson-agx-thor-baseboard"
				(path ""
					(reference "D19")
					(unit 1)
				)
			)
		)
	)
	(symbol
		(lib_id "antmicropower:GND")
		(at 364.49 203.2 0)
		(mirror y)
		(unit 1)
		(exclude_from_sim no)
		(in_bom yes)
		(on_board yes)
		(dnp no)
		(property "Reference" "#PWR0227"
			(at 364.49 209.55 0)
			(effects
				(font
					(size 1.27 1.27)
				)
				(justify left bottom)
				(hide yes)
			)
		)
		(property "Value" "GND"
			(at 364.49 207.01 0)
			(effects
				(font
					(size 1.27 1.27)
					(thickness 0.15)
				)
			)
		)
		(property "Footprint" ""
			(at 355.6 210.82 0)
			(effects
				(font
					(size 1.27 1.27)
					(thickness 0.15)
				)
				(justify left bottom)
				(hide yes)
			)
		)
		(property "Datasheet" ""
			(at 355.6 215.9 0)
			(effects
				(font
					(size 1.27 1.27)
					(thickness 0.15)
				)
				(justify left bottom)
				(hide yes)
			)
		)
		(property "Description" ""
			(at 364.49 203.2 0)
			(effects
				(font
					(size 1.27 1.27)
				)
				(hide yes)
			)
		)
		(property "Author" "Antmicro"
			(at 355.6 210.82 0)
			(effects
				(font
					(size 1.27 1.27)
					(thickness 0.15)
				)
				(justify left bottom)
				(hide yes)
			)
		)
		(property "License" "Apache-2.0"
			(at 355.6 213.36 0)
			(effects
				(font
					(size 1.27 1.27)
					(thickness 0.15)
				)
				(justify left bottom)
				(hide yes)
			)
		)
		(pin "1"
		)
		(instances
			(project "usb_debug_pd"
				(path ""
					(reference "#PWR?")
					(unit 1)
				)
			)
			(project "jetson-agx-thor-baseboard"
				(path ""
					(reference "#PWR0227")
					(unit 1)
				)
			)
		)
	)
	(symbol
		(lib_id "antmicropower:+3V3")
		(at 26.67 203.2 0)
		(unit 1)
		(exclude_from_sim no)
		(in_bom yes)
		(on_board yes)
		(dnp no)
		(fields_autoplaced yes)
		(property "Reference" "#PWR0215"
			(at 41.91 203.2 0)
			(effects
				(font
					(size 1.27 1.27)
					(thickness 0.15)
				)
				(justify left bottom)
				(hide yes)
			)
		)
		(property "Value" "FLASH_PWR"
			(at 26.67 198.12 0)
			(effects
				(font
					(size 1.27 1.27)
					(thickness 0.15)
				)
			)
		)
		(property "Footprint" ""
			(at 41.91 210.82 0)
			(effects
				(font
					(size 1.27 1.27)
					(thickness 0.15)
				)
				(justify left bottom)
				(hide yes)
			)
		)
		(property "Datasheet" ""
			(at 41.91 213.36 0)
			(effects
				(font
					(size 1.27 1.27)
					(thickness 0.15)
				)
				(justify left bottom)
				(hide yes)
			)
		)
		(property "Description" ""
			(at 26.67 203.2 0)
			(effects
				(font
					(size 1.27 1.27)
				)
				(hide yes)
			)
		)
		(property "Author" "Antmicro"
			(at 41.91 205.74 0)
			(effects
				(font
					(size 1.27 1.27)
					(thickness 0.15)
				)
				(justify left bottom)
				(hide yes)
			)
		)
		(property "License" "Apache-2.0"
			(at 41.91 208.28 0)
			(effects
				(font
					(size 1.27 1.27)
					(thickness 0.15)
				)
				(justify left bottom)
				(hide yes)
			)
		)
		(pin "1"
		)
		(instances
			(project "usb_debug_pd"
				(path ""
					(reference "#PWR?")
					(unit 1)
				)
			)
			(project "jetson-agx-thor-baseboard"
				(path ""
					(reference "#PWR0215")
					(unit 1)
				)
			)
		)
	)
	(symbol
		(lib_id "antmicropower:+3V3")
		(at 245.11 217.17 0)
		(unit 1)
		(exclude_from_sim no)
		(in_bom yes)
		(on_board yes)
		(dnp no)
		(property "Reference" "#PWR0229"
			(at 245.11 220.98 0)
			(effects
				(font
					(size 1.27 1.27)
				)
				(justify left bottom)
				(hide yes)
			)
		)
		(property "Value" "+3V3"
			(at 241.935 213.995 0)
			(effects
				(font
					(size 1.27 1.27)
					(thickness 0.15)
				)
				(justify left bottom)
			)
		)
		(property "Footprint" ""
			(at 260.35 224.79 0)
			(effects
				(font
					(size 1.27 1.27)
					(thickness 0.15)
				)
				(justify left bottom)
				(hide yes)
			)
		)
		(property "Datasheet" ""
			(at 260.35 227.33 0)
			(effects
				(font
					(size 1.27 1.27)
					(thickness 0.15)
				)
				(justify left bottom)
				(hide yes)
			)
		)
		(property "Description" ""
			(at 245.11 217.17 0)
			(effects
				(font
					(size 1.27 1.27)
				)
				(hide yes)
			)
		)
		(property "Author" "Antmicro"
			(at 260.35 219.71 0)
			(effects
				(font
					(size 1.27 1.27)
					(thickness 0.15)
				)
				(justify left bottom)
				(hide yes)
			)
		)
		(property "License" "Apache-2.0"
			(at 260.35 222.25 0)
			(effects
				(font
					(size 1.27 1.27)
					(thickness 0.15)
				)
				(justify left bottom)
				(hide yes)
			)
		)
		(pin "1"
		)
		(instances
			(project "usb_debug_pd"
				(path ""
					(reference "#PWR?")
					(unit 1)
				)
			)
			(project "jetson-agx-thor-baseboard"
				(path ""
					(reference "#PWR0229")
					(unit 1)
				)
			)
		)
	)
	(symbol
		(lib_id "antmicropower:GND")
		(at 86.36 146.05 0)
		(mirror y)
		(unit 1)
		(exclude_from_sim no)
		(in_bom yes)
		(on_board yes)
		(dnp no)
		(property "Reference" "#PWR0506"
			(at 86.36 152.4 0)
			(effects
				(font
					(size 1.27 1.27)
				)
				(justify left bottom)
				(hide yes)
			)
		)
		(property "Value" "GND"
			(at 86.36 149.86 0)
			(effects
				(font
					(size 1.27 1.27)
					(thickness 0.15)
				)
			)
		)
		(property "Footprint" ""
			(at 77.47 153.67 0)
			(effects
				(font
					(size 1.27 1.27)
					(thickness 0.15)
				)
				(justify left bottom)
				(hide yes)
			)
		)
		(property "Datasheet" ""
			(at 77.47 158.75 0)
			(effects
				(font
					(size 1.27 1.27)
					(thickness 0.15)
				)
				(justify left bottom)
				(hide yes)
			)
		)
		(property "Description" ""
			(at 86.36 146.05 0)
			(effects
				(font
					(size 1.27 1.27)
				)
				(hide yes)
			)
		)
		(property "Author" "Antmicro"
			(at 77.47 153.67 0)
			(effects
				(font
					(size 1.27 1.27)
					(thickness 0.15)
				)
				(justify left bottom)
				(hide yes)
			)
		)
		(property "License" "Apache-2.0"
			(at 77.47 156.21 0)
			(effects
				(font
					(size 1.27 1.27)
					(thickness 0.15)
				)
				(justify left bottom)
				(hide yes)
			)
		)
		(pin "1"
		)
		(instances
			(project "usb_debug_pd"
				(path ""
					(reference "#PWR?")
					(unit 1)
				)
			)
			(project "jetson-agx-thor-baseboard"
				(path ""
					(reference "#PWR0506")
					(unit 1)
				)
			)
		)
	)
	(symbol
		(lib_id "antmicroResistors0402:R_0R_0402")
		(at 55.88 234.95 0)
		(unit 1)
		(exclude_from_sim no)
		(in_bom no)
		(on_board yes)
		(dnp yes)
		(property "Reference" "R101"
			(at 62.992 233.68 0)
			(effects
				(font
					(size 1.27 1.27)
					(thickness 0.15)
				)
			)
		)
		(property "Value" "R_0R_0402"
			(at 76.2 247.65 0)
			(effects
				(font
					(size 1.27 1.27)
					(thickness 0.15)
				)
				(justify left bottom)
				(hide yes)
			)
		)
		(property "Footprint" "antmicro-footprints:R_0402_1005Metric"
			(at 76.2 250.19 0)
			(effects
				(font
					(size 1.27 1.27)
					(thickness 0.15)
				)
				(justify left bottom)
				(hide yes)
			)
		)
		(property "Datasheet" "https://industrial.panasonic.com/cdbs/www-data/pdf/RDA0000/AOA0000C301.pdf"
			(at 76.2 252.73 0)
			(effects
				(font
					(size 1.27 1.27)
					(thickness 0.15)
				)
				(justify left bottom)
				(hide yes)
			)
		)
		(property "Description" "SMD Chip Resistor, Jumper, 0 ohm, 100 mW, 0402 [1005 Metric], Thick Film, General Purpose"
			(at 76.2 267.97 0)
			(effects
				(font
					(size 1.27 1.27)
				)
				(justify left bottom)
				(hide yes)
			)
		)
		(property "MPN" "ERJ2GE0R00X"
			(at 76.2 255.27 0)
			(effects
				(font
					(size 1.27 1.27)
					(thickness 0.15)
				)
				(justify left bottom)
				(hide yes)
			)
		)
		(property "Manufacturer" "Panasonic"
			(at 76.2 257.81 0)
			(effects
				(font
					(size 1.27 1.27)
					(thickness 0.15)
				)
				(justify left bottom)
				(hide yes)
			)
		)
		(property "License" "Apache-2.0"
			(at 76.2 260.35 0)
			(effects
				(font
					(size 1.27 1.27)
					(thickness 0.15)
				)
				(justify left bottom)
				(hide yes)
			)
		)
		(property "Author" "Antmicro"
			(at 76.2 262.89 0)
			(effects
				(font
					(size 1.27 1.27)
					(thickness 0.15)
				)
				(justify left bottom)
				(hide yes)
			)
		)
		(property "Val" "0R"
			(at 55.118 233.68 0)
			(effects
				(font
					(size 1.27 1.27)
					(thickness 0.15)
				)
			)
		)
		(property "Tolerance" "~"
			(at 76.2 245.11 0)
			(effects
				(font
					(size 1.27 1.27)
				)
				(justify left bottom)
				(hide yes)
			)
		)
		(property "Current" "1A"
			(at 76.2 265.43 0)
			(effects
				(font
					(size 1.27 1.27)
					(thickness 0.15)
				)
				(justify left bottom)
				(hide yes)
			)
		)
		(pin "2"
		)
		(pin "1"
		)
		(instances
			(project "jetson-agx-thor-baseboard"
				(path ""
					(reference "R101")
					(unit 1)
				)
			)
		)
	)
	(symbol
		(lib_id "antmicroResistors0402:R_0R_0402")
		(at 92.71 200.66 0)
		(unit 1)
		(exclude_from_sim no)
		(in_bom yes)
		(on_board yes)
		(dnp no)
		(property "Reference" "R381"
			(at 99.822 199.39 0)
			(effects
				(font
					(size 1.27 1.27)
					(thickness 0.15)
				)
			)
		)
		(property "Value" "R_0R_0402"
			(at 113.03 213.36 0)
			(effects
				(font
					(size 1.27 1.27)
					(thickness 0.15)
				)
				(justify left bottom)
				(hide yes)
			)
		)
		(property "Footprint" "antmicro-footprints:R_0402_1005Metric"
			(at 113.03 215.9 0)
			(effects
				(font
					(size 1.27 1.27)
					(thickness 0.15)
				)
				(justify left bottom)
				(hide yes)
			)
		)
		(property "Datasheet" "https://industrial.panasonic.com/cdbs/www-data/pdf/RDA0000/AOA0000C301.pdf"
			(at 113.03 218.44 0)
			(effects
				(font
					(size 1.27 1.27)
					(thickness 0.15)
				)
				(justify left bottom)
				(hide yes)
			)
		)
		(property "Description" "SMD Chip Resistor, Jumper, 0 ohm, 100 mW, 0402 [1005 Metric], Thick Film, General Purpose"
			(at 113.03 233.68 0)
			(effects
				(font
					(size 1.27 1.27)
				)
				(justify left bottom)
				(hide yes)
			)
		)
		(property "MPN" "ERJ2GE0R00X"
			(at 113.03 220.98 0)
			(effects
				(font
					(size 1.27 1.27)
					(thickness 0.15)
				)
				(justify left bottom)
				(hide yes)
			)
		)
		(property "Manufacturer" "Panasonic"
			(at 113.03 223.52 0)
			(effects
				(font
					(size 1.27 1.27)
					(thickness 0.15)
				)
				(justify left bottom)
				(hide yes)
			)
		)
		(property "License" "Apache-2.0"
			(at 113.03 226.06 0)
			(effects
				(font
					(size 1.27 1.27)
					(thickness 0.15)
				)
				(justify left bottom)
				(hide yes)
			)
		)
		(property "Author" "Antmicro"
			(at 113.03 228.6 0)
			(effects
				(font
					(size 1.27 1.27)
					(thickness 0.15)
				)
				(justify left bottom)
				(hide yes)
			)
		)
		(property "Val" "0R"
			(at 91.948 199.39 0)
			(effects
				(font
					(size 1.27 1.27)
					(thickness 0.15)
				)
			)
		)
		(property "Tolerance" "~"
			(at 113.03 210.82 0)
			(effects
				(font
					(size 1.27 1.27)
				)
				(justify left bottom)
				(hide yes)
			)
		)
		(property "Current" "1A"
			(at 113.03 231.14 0)
			(effects
				(font
					(size 1.27 1.27)
					(thickness 0.15)
				)
				(justify left bottom)
				(hide yes)
			)
		)
		(pin "2"
		)
		(pin "1"
		)
		(instances
			(project ""
				(path ""
					(reference "R381")
					(unit 1)
				)
			)
		)
	)
	(symbol
		(lib_id "antmicroMemory:W25Q80DV_USON")
		(at 339.09 205.74 0)
		(unit 1)
		(exclude_from_sim no)
		(in_bom yes)
		(on_board yes)
		(dnp no)
		(property "Reference" "U29"
			(at 348.615 199.39 0)
			(effects
				(font
					(size 1.27 1.27)
				)
			)
		)
		(property "Value" "W25Q80DV_USON"
			(at 377.19 214.63 0)
			(effects
				(font
					(size 1.27 1.27)
					(thickness 0.15)
				)
				(justify left bottom)
				(hide yes)
			)
		)
		(property "Footprint" "antmicro-footprints:USON-8_2x3mm_P0.5mm"
			(at 377.19 217.17 0)
			(effects
				(font
					(size 1.27 1.27)
					(thickness 0.15)
				)
				(justify left bottom)
				(hide yes)
			)
		)
		(property "Datasheet" "https://www.mouser.com/datasheet/2/949/w25q80dv_dl_revh_10022015-1489677.pdf"
			(at 377.19 219.71 0)
			(effects
				(font
					(size 1.27 1.27)
					(thickness 0.15)
				)
				(justify left bottom)
				(hide yes)
			)
		)
		(property "Description" "FLASH - NOR Memory IC 8Mbit SPI - Quad I/O 104 MHz 8-USON (2x3)"
			(at 339.09 205.74 0)
			(effects
				(font
					(size 1.27 1.27)
				)
				(hide yes)
			)
		)
		(property "MPN" "W25Q80DVUXIE TR"
			(at 348.615 201.93 0)
			(effects
				(font
					(size 1.27 1.27)
					(thickness 0.15)
				)
			)
		)
		(property "Manufacturer" "Winbond"
			(at 377.19 224.79 0)
			(effects
				(font
					(size 1.27 1.27)
					(thickness 0.15)
				)
				(justify left bottom)
				(hide yes)
			)
		)
		(property "Author" "Antmicro"
			(at 377.19 227.33 0)
			(effects
				(font
					(size 1.27 1.27)
					(thickness 0.15)
				)
				(justify left bottom)
				(hide yes)
			)
		)
		(property "License" "Apache-2.0"
			(at 377.19 229.87 0)
			(effects
				(font
					(size 1.27 1.27)
					(thickness 0.15)
				)
				(justify left bottom)
				(hide yes)
			)
		)
		(pin "1"
		)
		(pin "2"
		)
		(pin "3"
		)
		(pin "4"
		)
		(pin "5"
		)
		(pin "6"
		)
		(pin "7"
		)
		(pin "8"
		)
		(pin "EP"
		)
		(instances
			(project "usb_debug_pd"
				(path ""
					(reference "U?")
					(unit 1)
				)
			)
			(project "jetson-agx-thor-baseboard"
				(path ""
					(reference "U29")
					(unit 1)
				)
			)
		)
	)
	(symbol
		(lib_id "antmicroCapacitors0402:C_100n_0402")
		(at 364.49 201.93 90)
		(unit 1)
		(exclude_from_sim no)
		(in_bom yes)
		(on_board yes)
		(dnp no)
		(fields_autoplaced yes)
		(property "Reference" "C122"
			(at 367.03 198.1136 90)
			(effects
				(font
					(size 1.27 1.27)
				)
				(justify right)
			)
		)
		(property "Value" "C_100n_0402"
			(at 374.65 181.61 0)
			(effects
				(font
					(size 1.27 1.27)
					(thickness 0.15)
				)
				(justify left bottom)
				(hide yes)
			)
		)
		(property "Footprint" "antmicro-footprints:C_0402_1005Metric"
			(at 377.19 181.61 0)
			(effects
				(font
					(size 1.27 1.27)
					(thickness 0.15)
				)
				(justify left bottom)
				(hide yes)
			)
		)
		(property "Datasheet" "https://www.murata.com/products/productdetail?partno=GRM155R61H104KE14%23"
			(at 379.73 181.61 0)
			(effects
				(font
					(size 1.27 1.27)
					(thickness 0.15)
				)
				(justify left bottom)
				(hide yes)
			)
		)
		(property "Description" "SMD Multilayer Ceramic Capacitor, 0.1 µF, 50 V, 0402 [1005 Metric], ± 10%, X5R, GRM Series"
			(at 364.49 201.93 0)
			(effects
				(font
					(size 1.27 1.27)
				)
				(hide yes)
			)
		)
		(property "Manufacturer" "Murata"
			(at 384.81 181.61 0)
			(effects
				(font
					(size 1.27 1.27)
					(thickness 0.15)
				)
				(justify left bottom)
				(hide yes)
			)
		)
		(property "MPN" "GRM155R61H104KE14D"
			(at 382.27 181.61 0)
			(effects
				(font
					(size 1.27 1.27)
					(thickness 0.15)
				)
				(justify left bottom)
				(hide yes)
			)
		)
		(property "Val" "100n"
			(at 367.03 200.6536 90)
			(effects
				(font
					(size 1.27 1.27)
					(thickness 0.15)
				)
				(justify right)
			)
		)
		(property "License" "Apache-2.0"
			(at 387.35 181.61 0)
			(effects
				(font
					(size 1.27 1.27)
					(thickness 0.15)
				)
				(justify left bottom)
				(hide yes)
			)
		)
		(property "Author" "Antmicro"
			(at 389.89 181.61 0)
			(effects
				(font
					(size 1.27 1.27)
					(thickness 0.15)
				)
				(justify left bottom)
				(hide yes)
			)
		)
		(property "Voltage" "50V"
			(at 392.43 181.61 0)
			(effects
				(font
					(size 1.27 1.27)
				)
				(justify left bottom)
				(hide yes)
			)
		)
		(property "Dielectric" "X5R"
			(at 394.97 181.61 0)
			(effects
				(font
					(size 1.27 1.27)
				)
				(justify left bottom)
				(hide yes)
			)
		)
		(pin "1"
		)
		(pin "2"
		)
		(instances
			(project "usb_debug_pd"
				(path ""
					(reference "C?")
					(unit 1)
				)
			)
			(project "jetson-agx-thor-baseboard"
				(path ""
					(reference "C122")
					(unit 1)
				)
			)
		)
	)
	(symbol
		(lib_id "antmicropower:GND")
		(at 347.98 39.37 0)
		(mirror y)
		(unit 1)
		(exclude_from_sim no)
		(in_bom yes)
		(on_board yes)
		(dnp no)
		(property "Reference" "#PWR0278"
			(at 347.98 45.72 0)
			(effects
				(font
					(size 1.27 1.27)
				)
				(justify left bottom)
				(hide yes)
			)
		)
		(property "Value" "GND"
			(at 347.98 43.18 0)
			(effects
				(font
					(size 1.27 1.27)
					(thickness 0.15)
				)
			)
		)
		(property "Footprint" ""
			(at 339.09 46.99 0)
			(effects
				(font
					(size 1.27 1.27)
					(thickness 0.15)
				)
				(justify left bottom)
				(hide yes)
			)
		)
		(property "Datasheet" ""
			(at 339.09 52.07 0)
			(effects
				(font
					(size 1.27 1.27)
					(thickness 0.15)
				)
				(justify left bottom)
				(hide yes)
			)
		)
		(property "Description" ""
			(at 347.98 39.37 0)
			(effects
				(font
					(size 1.27 1.27)
				)
				(hide yes)
			)
		)
		(property "Author" "Antmicro"
			(at 339.09 46.99 0)
			(effects
				(font
					(size 1.27 1.27)
					(thickness 0.15)
				)
				(justify left bottom)
				(hide yes)
			)
		)
		(property "License" "Apache-2.0"
			(at 339.09 49.53 0)
			(effects
				(font
					(size 1.27 1.27)
					(thickness 0.15)
				)
				(justify left bottom)
				(hide yes)
			)
		)
		(pin "1"
		)
		(instances
			(project "usb_debug_pd"
				(path ""
					(reference "#PWR?")
					(unit 1)
				)
			)
			(project "jetson-agx-thor-baseboard"
				(path ""
					(reference "#PWR0278")
					(unit 1)
				)
			)
		)
	)
	(symbol
		(lib_id "antmicroCapacitorsmisc:C_22u_25V_0805")
		(at 327.66 33.02 270)
		(unit 1)
		(exclude_from_sim no)
		(in_bom yes)
		(on_board yes)
		(dnp no)
		(fields_autoplaced yes)
		(property "Reference" "C151"
			(at 330.2 33.0262 90)
			(effects
				(font
					(size 1.27 1.27)
				)
				(justify left)
			)
		)
		(property "Value" "C_22u_25V_0805"
			(at 317.5 53.34 0)
			(effects
				(font
					(size 1.27 1.27)
					(thickness 0.15)
				)
				(justify left bottom)
				(hide yes)
			)
		)
		(property "Footprint" "antmicro-footprints:C_0805_2012Metric"
			(at 314.96 53.34 0)
			(effects
				(font
					(size 1.27 1.27)
					(thickness 0.15)
				)
				(justify left bottom)
				(hide yes)
			)
		)
		(property "Datasheet" "https://product.samsungsem.com/mlcc/CL21A226MAYNNN.do"
			(at 312.42 53.34 0)
			(effects
				(font
					(size 1.27 1.27)
					(thickness 0.15)
				)
				(justify left bottom)
				(hide yes)
			)
		)
		(property "Description" "SMT Multilayer Ceramic Capacitor, 22uF, +/-20%, 25V, X5R, 0805 [2012 Metric]"
			(at 327.66 33.02 0)
			(effects
				(font
					(size 1.27 1.27)
				)
				(hide yes)
			)
		)
		(property "Manufacturer" "Samsung Electro-Mechanics"
			(at 307.34 53.34 0)
			(effects
				(font
					(size 1.27 1.27)
					(thickness 0.15)
				)
				(justify left bottom)
				(hide yes)
			)
		)
		(property "MPN" "CL21A226MAYNNNE"
			(at 309.88 53.34 0)
			(effects
				(font
					(size 1.27 1.27)
					(thickness 0.15)
				)
				(justify left bottom)
				(hide yes)
			)
		)
		(property "Val" "22u"
			(at 330.2 35.5663 90)
			(effects
				(font
					(size 1.27 1.27)
					(thickness 0.15)
				)
				(justify left)
			)
		)
		(property "License" "Apache-2.0"
			(at 304.8 53.34 0)
			(effects
				(font
					(size 1.27 1.27)
					(thickness 0.15)
				)
				(justify left bottom)
				(hide yes)
			)
		)
		(property "Author" "Antmicro"
			(at 302.26 53.34 0)
			(effects
				(font
					(size 1.27 1.27)
					(thickness 0.15)
				)
				(justify left bottom)
				(hide yes)
			)
		)
		(property "Voltage" "25V"
			(at 330.2 38.1062 90)
			(effects
				(font
					(size 1.27 1.27)
				)
				(justify left)
			)
		)
		(property "Dielectric" "X5R"
			(at 297.18 53.34 0)
			(effects
				(font
					(size 1.27 1.27)
				)
				(justify left bottom)
				(hide yes)
			)
		)
		(property "Public" "False"
			(at 294.64 53.34 0)
			(effects
				(font
					(size 1.27 1.27)
				)
				(justify left bottom)
				(hide yes)
			)
		)
		(pin "1"
		)
		(pin "2"
		)
		(instances
			(project "usb_debug_pd"
				(path ""
					(reference "C?")
					(unit 1)
				)
			)
			(project "jetson-agx-thor-baseboard"
				(path ""
					(reference "C151")
					(unit 1)
				)
			)
		)
	)
	(symbol
		(lib_id "antmicroTestPoints:TP_0.75mm_SMD")
		(at 359.41 31.75 90)
		(unit 1)
		(exclude_from_sim no)
		(in_bom no)
		(on_board yes)
		(dnp no)
		(property "Reference" "TP62"
			(at 361.696 26.416 90)
			(effects
				(font
					(size 1.27 1.27)
				)
				(justify left)
			)
		)
		(property "Value" "TP_0.75mm_SMD"
			(at 363.22 21.59 0)
			(effects
				(font
					(size 1.27 1.27)
					(thickness 0.15)
				)
				(justify left bottom)
				(hide yes)
			)
		)
		(property "Footprint" "antmicro-footprints:TP_SMD_0.75mm"
			(at 365.76 21.59 0)
			(effects
				(font
					(size 1.27 1.27)
					(thickness 0.15)
				)
				(justify left bottom)
				(hide yes)
			)
		)
		(property "Datasheet" ""
			(at 372.11 13.97 0)
			(effects
				(font
					(size 1.27 1.27)
					(thickness 0.15)
				)
				(justify left bottom)
				(hide yes)
			)
		)
		(property "Description" "SMT test point"
			(at 359.41 31.75 0)
			(effects
				(font
					(size 1.27 1.27)
				)
				(hide yes)
			)
		)
		(property "MPN" ""
			(at 370.84 20.955 0)
			(effects
				(font
					(size 1.27 1.27)
					(thickness 0.15)
				)
				(justify left bottom)
				(hide yes)
			)
		)
		(property "Manufacturer" ""
			(at 365.76 20.955 0)
			(effects
				(font
					(size 1.27 1.27)
					(thickness 0.15)
				)
				(justify left bottom)
				(hide yes)
			)
		)
		(property "Author" "Antmicro"
			(at 368.3 21.59 0)
			(effects
				(font
					(size 1.27 1.27)
					(thickness 0.15)
				)
				(justify left bottom)
				(hide yes)
			)
		)
		(property "License" "Apache-2.0"
			(at 370.84 21.59 0)
			(effects
				(font
					(size 1.27 1.27)
					(thickness 0.15)
				)
				(justify left bottom)
				(hide yes)
			)
		)
		(pin "1"
		)
		(instances
			(project "usb_debug_pd"
				(path ""
					(reference "TP?")
					(unit 1)
				)
			)
			(project "jetson-agx-thor-baseboard"
				(path ""
					(reference "TP62")
					(unit 1)
				)
			)
		)
	)
	(symbol
		(lib_id "antmicroResistors0402:R_0R_0402")
		(at 261.62 250.19 0)
		(mirror y)
		(unit 1)
		(exclude_from_sim no)
		(in_bom yes)
		(on_board yes)
		(dnp no)
		(property "Reference" "R112"
			(at 261.62 249.555 0)
			(effects
				(font
					(size 1.27 1.27)
				)
				(justify right bottom)
			)
		)
		(property "Value" "R_0R_0402"
			(at 241.3 262.89 0)
			(effects
				(font
					(size 1.27 1.27)
					(thickness 0.15)
				)
				(justify left bottom)
				(hide yes)
			)
		)
		(property "Footprint" "antmicro-footprints:R_0402_1005Metric"
			(at 241.3 265.43 0)
			(effects
				(font
					(size 1.27 1.27)
					(thickness 0.15)
				)
				(justify left bottom)
				(hide yes)
			)
		)
		(property "Datasheet" "https://industrial.panasonic.com/cdbs/www-data/pdf/RDA0000/AOA0000C301.pdf"
			(at 241.3 267.97 0)
			(effects
				(font
					(size 1.27 1.27)
					(thickness 0.15)
				)
				(justify left bottom)
				(hide yes)
			)
		)
		(property "Description" "SMD Chip Resistor, Jumper, 0 ohm, 100 mW, 0402 [1005 Metric], Thick Film, General Purpose"
			(at 261.62 250.19 0)
			(effects
				(font
					(size 1.27 1.27)
				)
				(hide yes)
			)
		)
		(property "Manufacturer" "Panasonic"
			(at 241.3 273.05 0)
			(effects
				(font
					(size 1.27 1.27)
					(thickness 0.15)
				)
				(justify left bottom)
				(hide yes)
			)
		)
		(property "MPN" "ERJ2GE0R00X"
			(at 241.3 270.51 0)
			(effects
				(font
					(size 1.27 1.27)
					(thickness 0.15)
				)
				(justify left bottom)
				(hide yes)
			)
		)
		(property "Val" "0R"
			(at 254 249.555 0)
			(effects
				(font
					(size 1.27 1.27)
					(thickness 0.15)
				)
				(justify right bottom)
			)
		)
		(property "License" "Apache-2.0"
			(at 241.3 275.59 0)
			(effects
				(font
					(size 1.27 1.27)
					(thickness 0.15)
				)
				(justify left bottom)
				(hide yes)
			)
		)
		(property "Author" "Antmicro"
			(at 241.3 278.13 0)
			(effects
				(font
					(size 1.27 1.27)
					(thickness 0.15)
				)
				(justify left bottom)
				(hide yes)
			)
		)
		(property "Tolerance" "~"
			(at 241.3 260.35 0)
			(effects
				(font
					(size 1.27 1.27)
				)
				(justify left bottom)
				(hide yes)
			)
		)
		(property "Current" "1A"
			(at 241.3 280.67 0)
			(effects
				(font
					(size 1.27 1.27)
					(thickness 0.15)
				)
				(justify left bottom)
				(hide yes)
			)
		)
		(pin "1"
		)
		(pin "2"
		)
		(instances
			(project "usb_debug_pd"
				(path ""
					(reference "R?")
					(unit 1)
				)
			)
			(project "jetson-agx-thor-baseboard"
				(path ""
					(reference "R112")
					(unit 1)
				)
			)
		)
	)
	(symbol
		(lib_id "antmicroCapacitors0402:C_10u_0402")
		(at 161.29 196.85 90)
		(unit 1)
		(exclude_from_sim no)
		(in_bom yes)
		(on_board yes)
		(dnp no)
		(property "Reference" "C121"
			(at 161.925 192.405 90)
			(effects
				(font
					(size 1.27 1.27)
					(thickness 0.15)
				)
				(justify right)
			)
		)
		(property "Value" "C_10u_0402"
			(at 171.45 176.53 0)
			(effects
				(font
					(size 1.27 1.27)
					(thickness 0.15)
				)
				(justify left bottom)
				(hide yes)
			)
		)
		(property "Footprint" "antmicro-footprints:C_0402_1005Metric"
			(at 173.99 176.53 0)
			(effects
				(font
					(size 1.27 1.27)
					(thickness 0.15)
				)
				(justify left bottom)
				(hide yes)
			)
		)
		(property "Datasheet" "https://www.yageo.com/en/Chart/Download/pdf/CC0402MRX5R5BB106"
			(at 176.53 176.53 0)
			(effects
				(font
					(size 1.27 1.27)
					(thickness 0.15)
				)
				(justify left bottom)
				(hide yes)
			)
		)
		(property "Description" "SMD Multilayer Ceramic Capacitor, 10 µF, 6.3 V, 0402 [1005 Metric], ± 20%, X5R, CC Series"
			(at 161.29 196.85 0)
			(effects
				(font
					(size 1.27 1.27)
				)
				(hide yes)
			)
		)
		(property "MPN" "CC0402MRX5R5BB106"
			(at 179.07 176.53 0)
			(effects
				(font
					(size 1.27 1.27)
					(thickness 0.15)
				)
				(justify left bottom)
				(hide yes)
			)
		)
		(property "Manufacturer" "YAGEO"
			(at 181.61 176.53 0)
			(effects
				(font
					(size 1.27 1.27)
					(thickness 0.15)
				)
				(justify left bottom)
				(hide yes)
			)
		)
		(property "License" "Apache-2.0"
			(at 184.15 176.53 0)
			(effects
				(font
					(size 1.27 1.27)
					(thickness 0.15)
				)
				(justify left bottom)
				(hide yes)
			)
		)
		(property "Author" "Antmicro"
			(at 186.69 176.53 0)
			(effects
				(font
					(size 1.27 1.27)
					(thickness 0.15)
				)
				(justify left bottom)
				(hide yes)
			)
		)
		(property "Val" "10u"
			(at 161.925 196.215 90)
			(effects
				(font
					(size 1.27 1.27)
					(thickness 0.15)
				)
				(justify right)
			)
		)
		(property "Voltage" ""
			(at 189.23 176.53 0)
			(effects
				(font
					(size 1.27 1.27)
				)
				(justify left bottom)
				(hide yes)
			)
		)
		(property "Dielectric" ""
			(at 191.77 176.53 0)
			(effects
				(font
					(size 1.27 1.27)
				)
				(justify left bottom)
				(hide yes)
			)
		)
		(pin "1"
		)
		(pin "2"
		)
		(instances
			(project "usb_debug_pd"
				(path ""
					(reference "C?")
					(unit 1)
				)
			)
			(project "jetson-agx-thor-baseboard"
				(path ""
					(reference "C121")
					(unit 1)
				)
			)
		)
	)
	(symbol
		(lib_id "antmicropower:GND")
		(at 337.82 39.37 0)
		(mirror y)
		(unit 1)
		(exclude_from_sim no)
		(in_bom yes)
		(on_board yes)
		(dnp no)
		(property "Reference" "#PWR0275"
			(at 337.82 45.72 0)
			(effects
				(font
					(size 1.27 1.27)
				)
				(justify left bottom)
				(hide yes)
			)
		)
		(property "Value" "GND"
			(at 337.82 43.18 0)
			(effects
				(font
					(size 1.27 1.27)
					(thickness 0.15)
				)
			)
		)
		(property "Footprint" ""
			(at 328.93 46.99 0)
			(effects
				(font
					(size 1.27 1.27)
					(thickness 0.15)
				)
				(justify left bottom)
				(hide yes)
			)
		)
		(property "Datasheet" ""
			(at 328.93 52.07 0)
			(effects
				(font
					(size 1.27 1.27)
					(thickness 0.15)
				)
				(justify left bottom)
				(hide yes)
			)
		)
		(property "Description" ""
			(at 337.82 39.37 0)
			(effects
				(font
					(size 1.27 1.27)
				)
				(hide yes)
			)
		)
		(property "Author" "Antmicro"
			(at 328.93 46.99 0)
			(effects
				(font
					(size 1.27 1.27)
					(thickness 0.15)
				)
				(justify left bottom)
				(hide yes)
			)
		)
		(property "License" "Apache-2.0"
			(at 328.93 49.53 0)
			(effects
				(font
					(size 1.27 1.27)
					(thickness 0.15)
				)
				(justify left bottom)
				(hide yes)
			)
		)
		(pin "1"
		)
		(instances
			(project "usb_debug_pd"
				(path ""
					(reference "#PWR?")
					(unit 1)
				)
			)
			(project "jetson-agx-thor-baseboard"
				(path ""
					(reference "#PWR0275")
					(unit 1)
				)
			)
		)
	)
	(symbol
		(lib_id "antmicropower:GND")
		(at 359.41 219.71 0)
		(mirror y)
		(unit 1)
		(exclude_from_sim no)
		(in_bom yes)
		(on_board yes)
		(dnp no)
		(property "Reference" "#PWR0226"
			(at 359.41 226.06 0)
			(effects
				(font
					(size 1.27 1.27)
				)
				(justify left bottom)
				(hide yes)
			)
		)
		(property "Value" "GND"
			(at 359.41 223.52 0)
			(effects
				(font
					(size 1.27 1.27)
					(thickness 0.15)
				)
			)
		)
		(property "Footprint" ""
			(at 350.52 227.33 0)
			(effects
				(font
					(size 1.27 1.27)
					(thickness 0.15)
				)
				(justify left bottom)
				(hide yes)
			)
		)
		(property "Datasheet" ""
			(at 350.52 232.41 0)
			(effects
				(font
					(size 1.27 1.27)
					(thickness 0.15)
				)
				(justify left bottom)
				(hide yes)
			)
		)
		(property "Description" ""
			(at 359.41 219.71 0)
			(effects
				(font
					(size 1.27 1.27)
				)
				(hide yes)
			)
		)
		(property "Author" "Antmicro"
			(at 350.52 227.33 0)
			(effects
				(font
					(size 1.27 1.27)
					(thickness 0.15)
				)
				(justify left bottom)
				(hide yes)
			)
		)
		(property "License" "Apache-2.0"
			(at 350.52 229.87 0)
			(effects
				(font
					(size 1.27 1.27)
					(thickness 0.15)
				)
				(justify left bottom)
				(hide yes)
			)
		)
		(pin "1"
		)
		(instances
			(project "usb_debug_pd"
				(path ""
					(reference "#PWR?")
					(unit 1)
				)
			)
			(project "jetson-agx-thor-baseboard"
				(path ""
					(reference "#PWR0226")
					(unit 1)
				)
			)
		)
	)
	(symbol
		(lib_id "antmicroTestPoints:TP_0.75mm_SMD")
		(at 35.56 116.84 180)
		(unit 1)
		(exclude_from_sim no)
		(in_bom no)
		(on_board yes)
		(dnp no)
		(property "Reference" "TP92"
			(at 31.242 116.84 0)
			(effects
				(font
					(size 1.27 1.27)
					(thickness 0.15)
				)
				(justify left)
			)
		)
		(property "Value" "TP_0.75mm_SMD"
			(at 25.4 113.03 0)
			(effects
				(font
					(size 1.27 1.27)
					(thickness 0.15)
				)
				(justify left bottom)
				(hide yes)
			)
		)
		(property "Footprint" "antmicro-footprints:TP_SMD_0.75mm"
			(at 25.4 110.49 0)
			(effects
				(font
					(size 1.27 1.27)
					(thickness 0.15)
				)
				(justify left bottom)
				(hide yes)
			)
		)
		(property "Datasheet" ""
			(at 17.78 104.14 0)
			(effects
				(font
					(size 1.27 1.27)
					(thickness 0.15)
				)
				(justify left bottom)
				(hide yes)
			)
		)
		(property "Description" "SMT test point"
			(at 35.56 116.84 0)
			(effects
				(font
					(size 1.27 1.27)
				)
				(hide yes)
			)
		)
		(property "MPN" ""
			(at 24.765 105.41 0)
			(effects
				(font
					(size 1.27 1.27)
					(thickness 0.15)
				)
				(justify left bottom)
				(hide yes)
			)
		)
		(property "Manufacturer" ""
			(at 24.765 110.49 0)
			(effects
				(font
					(size 1.27 1.27)
					(thickness 0.15)
				)
				(justify left bottom)
				(hide yes)
			)
		)
		(property "Author" "Antmicro"
			(at 25.4 107.95 0)
			(effects
				(font
					(size 1.27 1.27)
					(thickness 0.15)
				)
				(justify left bottom)
				(hide yes)
			)
		)
		(property "License" "Apache-2.0"
			(at 25.4 105.41 0)
			(effects
				(font
					(size 1.27 1.27)
					(thickness 0.15)
				)
				(justify left bottom)
				(hide yes)
			)
		)
		(pin "1"
		)
		(instances
			(project "jetson-agx-thor-baseboard"
				(path ""
					(reference "TP92")
					(unit 1)
				)
			)
		)
	)
	(symbol
		(lib_id "antmicroCapacitors0402:C_100n_0402")
		(at 209.55 57.15 90)
		(mirror x)
		(unit 1)
		(exclude_from_sim no)
		(in_bom yes)
		(on_board yes)
		(dnp no)
		(fields_autoplaced yes)
		(property "Reference" "C143"
			(at 207.01 58.4263 90)
			(effects
				(font
					(size 1.27 1.27)
				)
				(justify left)
			)
		)
		(property "Value" "C_100n_0402"
			(at 219.71 77.47 0)
			(effects
				(font
					(size 1.27 1.27)
					(thickness 0.15)
				)
				(justify left bottom)
				(hide yes)
			)
		)
		(property "Footprint" "antmicro-footprints:C_0402_1005Metric"
			(at 222.25 77.47 0)
			(effects
				(font
					(size 1.27 1.27)
					(thickness 0.15)
				)
				(justify left bottom)
				(hide yes)
			)
		)
		(property "Datasheet" "https://www.murata.com/products/productdetail?partno=GRM155R61H104KE14%23"
			(at 224.79 77.47 0)
			(effects
				(font
					(size 1.27 1.27)
					(thickness 0.15)
				)
				(justify left bottom)
				(hide yes)
			)
		)
		(property "Description" "SMD Multilayer Ceramic Capacitor, 0.1 µF, 50 V, 0402 [1005 Metric], ± 10%, X5R, GRM Series"
			(at 209.55 57.15 0)
			(effects
				(font
					(size 1.27 1.27)
				)
				(hide yes)
			)
		)
		(property "MPN" "GRM155R61H104KE14D"
			(at 227.33 77.47 0)
			(effects
				(font
					(size 1.27 1.27)
					(thickness 0.15)
				)
				(justify left bottom)
				(hide yes)
			)
		)
		(property "Manufacturer" "Murata"
			(at 229.87 77.47 0)
			(effects
				(font
					(size 1.27 1.27)
					(thickness 0.15)
				)
				(justify left bottom)
				(hide yes)
			)
		)
		(property "Val" "100n"
			(at 207.01 60.9663 90)
			(effects
				(font
					(size 1.27 1.27)
					(thickness 0.15)
				)
				(justify left)
			)
		)
		(property "License" "Apache-2.0"
			(at 232.41 77.47 0)
			(effects
				(font
					(size 1.27 1.27)
					(thickness 0.15)
				)
				(justify left bottom)
				(hide yes)
			)
		)
		(property "Author" "Antmicro"
			(at 234.95 77.47 0)
			(effects
				(font
					(size 1.27 1.27)
					(thickness 0.15)
				)
				(justify left bottom)
				(hide yes)
			)
		)
		(property "Voltage" "50V"
			(at 237.49 77.47 0)
			(effects
				(font
					(size 1.27 1.27)
				)
				(justify left bottom)
				(hide yes)
			)
		)
		(property "Dielectric" "X5R"
			(at 240.03 77.47 0)
			(effects
				(font
					(size 1.27 1.27)
				)
				(justify left bottom)
				(hide yes)
			)
		)
		(pin "1"
		)
		(pin "2"
		)
		(instances
			(project "usb_debug_pd"
				(path ""
					(reference "C?")
					(unit 1)
				)
			)
			(project "jetson-agx-thor-baseboard"
				(path ""
					(reference "C143")
					(unit 1)
				)
			)
		)
	)
	(symbol
		(lib_id "antmicropower:GND")
		(at 195.58 124.46 0)
		(unit 1)
		(exclude_from_sim no)
		(in_bom yes)
		(on_board yes)
		(dnp no)
		(property "Reference" "#PWR0255"
			(at 195.58 130.81 0)
			(effects
				(font
					(size 1.27 1.27)
				)
				(justify left bottom)
				(hide yes)
			)
		)
		(property "Value" "GND"
			(at 195.58 128.27 0)
			(effects
				(font
					(size 1.27 1.27)
					(thickness 0.15)
				)
			)
		)
		(property "Footprint" ""
			(at 204.47 132.08 0)
			(effects
				(font
					(size 1.27 1.27)
					(thickness 0.15)
				)
				(justify left bottom)
				(hide yes)
			)
		)
		(property "Datasheet" ""
			(at 204.47 137.16 0)
			(effects
				(font
					(size 1.27 1.27)
					(thickness 0.15)
				)
				(justify left bottom)
				(hide yes)
			)
		)
		(property "Description" ""
			(at 195.58 124.46 0)
			(effects
				(font
					(size 1.27 1.27)
				)
				(hide yes)
			)
		)
		(property "Author" "Antmicro"
			(at 204.47 132.08 0)
			(effects
				(font
					(size 1.27 1.27)
					(thickness 0.15)
				)
				(justify left bottom)
				(hide yes)
			)
		)
		(property "License" "Apache-2.0"
			(at 204.47 134.62 0)
			(effects
				(font
					(size 1.27 1.27)
					(thickness 0.15)
				)
				(justify left bottom)
				(hide yes)
			)
		)
		(pin "1"
		)
		(instances
			(project "usb_debug_pd"
				(path ""
					(reference "#PWR?")
					(unit 1)
				)
			)
			(project "jetson-agx-thor-baseboard"
				(path ""
					(reference "#PWR0255")
					(unit 1)
				)
			)
		)
	)
	(symbol
		(lib_id "antmicropower:GND")
		(at 306.07 44.45 0)
		(mirror y)
		(unit 1)
		(exclude_from_sim no)
		(in_bom yes)
		(on_board yes)
		(dnp no)
		(property "Reference" "#PWR0280"
			(at 306.07 50.8 0)
			(effects
				(font
					(size 1.27 1.27)
				)
				(justify left bottom)
				(hide yes)
			)
		)
		(property "Value" "GND"
			(at 306.07 48.26 0)
			(effects
				(font
					(size 1.27 1.27)
					(thickness 0.15)
				)
			)
		)
		(property "Footprint" ""
			(at 297.18 52.07 0)
			(effects
				(font
					(size 1.27 1.27)
					(thickness 0.15)
				)
				(justify left bottom)
				(hide yes)
			)
		)
		(property "Datasheet" ""
			(at 297.18 57.15 0)
			(effects
				(font
					(size 1.27 1.27)
					(thickness 0.15)
				)
				(justify left bottom)
				(hide yes)
			)
		)
		(property "Description" ""
			(at 306.07 44.45 0)
			(effects
				(font
					(size 1.27 1.27)
				)
				(hide yes)
			)
		)
		(property "Author" "Antmicro"
			(at 297.18 52.07 0)
			(effects
				(font
					(size 1.27 1.27)
					(thickness 0.15)
				)
				(justify left bottom)
				(hide yes)
			)
		)
		(property "License" "Apache-2.0"
			(at 297.18 54.61 0)
			(effects
				(font
					(size 1.27 1.27)
					(thickness 0.15)
				)
				(justify left bottom)
				(hide yes)
			)
		)
		(pin "1"
		)
		(instances
			(project "usb_debug_pd"
				(path ""
					(reference "#PWR?")
					(unit 1)
				)
			)
			(project "jetson-agx-thor-baseboard"
				(path ""
					(reference "#PWR0280")
					(unit 1)
				)
			)
		)
	)
	(symbol
		(lib_id "antmicroCapacitors0402:C_100n_0402")
		(at 134.62 66.04 270)
		(unit 1)
		(exclude_from_sim no)
		(in_bom yes)
		(on_board yes)
		(dnp no)
		(fields_autoplaced yes)
		(property "Reference" "C133"
			(at 132.08 67.3163 90)
			(effects
				(font
					(size 1.27 1.27)
				)
				(justify right)
			)
		)
		(property "Value" "C_100n_0402"
			(at 124.46 86.36 0)
			(effects
				(font
					(size 1.27 1.27)
					(thickness 0.15)
				)
				(justify left bottom)
				(hide yes)
			)
		)
		(property "Footprint" "antmicro-footprints:C_0402_1005Metric"
			(at 121.92 86.36 0)
			(effects
				(font
					(size 1.27 1.27)
					(thickness 0.15)
				)
				(justify left bottom)
				(hide yes)
			)
		)
		(property "Datasheet" "https://www.murata.com/products/productdetail?partno=GRM155R61H104KE14%23"
			(at 119.38 86.36 0)
			(effects
				(font
					(size 1.27 1.27)
					(thickness 0.15)
				)
				(justify left bottom)
				(hide yes)
			)
		)
		(property "Description" "SMD Multilayer Ceramic Capacitor, 0.1 µF, 50 V, 0402 [1005 Metric], ± 10%, X5R, GRM Series"
			(at 134.62 66.04 0)
			(effects
				(font
					(size 1.27 1.27)
				)
				(hide yes)
			)
		)
		(property "Manufacturer" "Murata"
			(at 114.3 86.36 0)
			(effects
				(font
					(size 1.27 1.27)
					(thickness 0.15)
				)
				(justify left bottom)
				(hide yes)
			)
		)
		(property "MPN" "GRM155R61H104KE14D"
			(at 116.84 86.36 0)
			(effects
				(font
					(size 1.27 1.27)
					(thickness 0.15)
				)
				(justify left bottom)
				(hide yes)
			)
		)
		(property "Val" "100n"
			(at 132.08 69.8563 90)
			(effects
				(font
					(size 1.27 1.27)
					(thickness 0.15)
				)
				(justify right)
			)
		)
		(property "License" "Apache-2.0"
			(at 111.76 86.36 0)
			(effects
				(font
					(size 1.27 1.27)
					(thickness 0.15)
				)
				(justify left bottom)
				(hide yes)
			)
		)
		(property "Author" "Antmicro"
			(at 109.22 86.36 0)
			(effects
				(font
					(size 1.27 1.27)
					(thickness 0.15)
				)
				(justify left bottom)
				(hide yes)
			)
		)
		(property "Voltage" "50V"
			(at 106.68 86.36 0)
			(effects
				(font
					(size 1.27 1.27)
				)
				(justify left bottom)
				(hide yes)
			)
		)
		(property "Dielectric" "X5R"
			(at 104.14 86.36 0)
			(effects
				(font
					(size 1.27 1.27)
				)
				(justify left bottom)
				(hide yes)
			)
		)
		(pin "1"
		)
		(pin "2"
		)
		(instances
			(project "usb_debug_pd"
				(path ""
					(reference "C?")
					(unit 1)
				)
			)
			(project "jetson-agx-thor-baseboard"
				(path ""
					(reference "C133")
					(unit 1)
				)
			)
		)
	)
	(symbol
		(lib_id "antmicropower:+5V")
		(at 214.63 73.66 0)
		(unit 1)
		(exclude_from_sim no)
		(in_bom yes)
		(on_board yes)
		(dnp no)
		(property "Reference" "#PWR0262"
			(at 214.63 77.47 0)
			(effects
				(font
					(size 1.27 1.27)
				)
				(justify left bottom)
				(hide yes)
			)
		)
		(property "Value" "+5V"
			(at 212.598 70.612 0)
			(effects
				(font
					(size 1.27 1.27)
					(thickness 0.15)
				)
				(justify left bottom)
			)
		)
		(property "Footprint" ""
			(at 229.87 81.28 0)
			(effects
				(font
					(size 1.27 1.27)
					(thickness 0.15)
				)
				(justify left bottom)
				(hide yes)
			)
		)
		(property "Datasheet" ""
			(at 229.87 83.82 0)
			(effects
				(font
					(size 1.27 1.27)
					(thickness 0.15)
				)
				(justify left bottom)
				(hide yes)
			)
		)
		(property "Description" ""
			(at 214.63 73.66 0)
			(effects
				(font
					(size 1.27 1.27)
				)
				(hide yes)
			)
		)
		(property "Author" "Antmicro"
			(at 229.87 81.28 0)
			(effects
				(font
					(size 1.27 1.27)
					(thickness 0.15)
				)
				(justify left bottom)
				(hide yes)
			)
		)
		(property "License" "Apache-2.0"
			(at 229.87 83.82 0)
			(effects
				(font
					(size 1.27 1.27)
					(thickness 0.15)
				)
				(justify left bottom)
				(hide yes)
			)
		)
		(pin "1"
		)
		(instances
			(project "usb_debug_pd"
				(path ""
					(reference "#PWR?")
					(unit 1)
				)
			)
			(project "jetson-agx-thor-baseboard"
				(path ""
					(reference "#PWR0262")
					(unit 1)
				)
			)
		)
	)
	(symbol
		(lib_id "antmicroResistors0402:R_10k_0402")
		(at 212.09 114.3 0)
		(mirror y)
		(unit 1)
		(exclude_from_sim no)
		(in_bom yes)
		(on_board yes)
		(dnp no)
		(property "Reference" "R145"
			(at 207.01 113.665 0)
			(effects
				(font
					(size 1.27 1.27)
				)
				(justify left bottom)
			)
		)
		(property "Value" "R_10k_0402"
			(at 191.77 127 0)
			(effects
				(font
					(size 1.27 1.27)
					(thickness 0.15)
				)
				(justify left bottom)
				(hide yes)
			)
		)
		(property "Footprint" "antmicro-footprints:R_0402_1005Metric"
			(at 191.77 129.54 0)
			(effects
				(font
					(size 1.27 1.27)
					(thickness 0.15)
				)
				(justify left bottom)
				(hide yes)
			)
		)
		(property "Datasheet" "https://www.bourns.com/docs/product-datasheets/cr.pdf"
			(at 191.77 132.08 0)
			(effects
				(font
					(size 1.27 1.27)
					(thickness 0.15)
				)
				(justify left bottom)
				(hide yes)
			)
		)
		(property "Description" "SMD Chip Resistor, 10 kohm, ± 1%, 62.5 mW, 0402 [1005 Metric], Thick Film, General Purpose"
			(at 212.09 114.3 0)
			(effects
				(font
					(size 1.27 1.27)
				)
				(hide yes)
			)
		)
		(property "Manufacturer" "Bourns"
			(at 191.77 137.16 0)
			(effects
				(font
					(size 1.27 1.27)
					(thickness 0.15)
				)
				(justify left bottom)
				(hide yes)
			)
		)
		(property "MPN" "CR0402-FX-1002GLF"
			(at 191.77 134.62 0)
			(effects
				(font
					(size 1.27 1.27)
					(thickness 0.15)
				)
				(justify left bottom)
				(hide yes)
			)
		)
		(property "Val" "10k"
			(at 215.9 113.665 0)
			(effects
				(font
					(size 1.27 1.27)
					(thickness 0.15)
				)
				(justify left bottom)
			)
		)
		(property "License" "Apache-2.0"
			(at 191.77 139.7 0)
			(effects
				(font
					(size 1.27 1.27)
					(thickness 0.15)
				)
				(justify left bottom)
				(hide yes)
			)
		)
		(property "Author" "Antmicro"
			(at 191.77 142.24 0)
			(effects
				(font
					(size 1.27 1.27)
					(thickness 0.15)
				)
				(justify left bottom)
				(hide yes)
			)
		)
		(property "Tolerance" "1%"
			(at 191.77 124.46 0)
			(effects
				(font
					(size 1.27 1.27)
				)
				(justify left bottom)
				(hide yes)
			)
		)
		(pin "1"
		)
		(pin "2"
		)
		(instances
			(project "usb_debug_pd"
				(path ""
					(reference "R?")
					(unit 1)
				)
			)
			(project "jetson-agx-thor-baseboard"
				(path ""
					(reference "R145")
					(unit 1)
				)
			)
		)
	)
	(symbol
		(lib_id "antmicroCapacitors0402:C_47p_0402")
		(at 270.51 118.11 90)
		(unit 1)
		(exclude_from_sim no)
		(in_bom yes)
		(on_board yes)
		(dnp no)
		(property "Reference" "C149"
			(at 267.97 114.2936 90)
			(effects
				(font
					(size 1.27 1.27)
					(thickness 0.15)
				)
				(justify left)
			)
		)
		(property "Value" "C_47p_0402"
			(at 280.67 97.79 0)
			(effects
				(font
					(size 1.27 1.27)
					(thickness 0.15)
				)
				(justify left bottom)
				(hide yes)
			)
		)
		(property "Footprint" "antmicro-footprints:C_0402_1005Metric"
			(at 283.21 97.79 0)
			(effects
				(font
					(size 1.27 1.27)
					(thickness 0.15)
				)
				(justify left bottom)
				(hide yes)
			)
		)
		(property "Datasheet" "https://www.kemet.com/en/us/capacitors/product/C0402C470J5GACTU.html"
			(at 285.75 97.79 0)
			(effects
				(font
					(size 1.27 1.27)
					(thickness 0.15)
				)
				(justify left bottom)
				(hide yes)
			)
		)
		(property "Description" "SMD Multilayer Ceramic Capacitor, 47 pF, 50 V, 0402 [1005 Metric], ± 5%, C0G / NP0, C Series KEMET"
			(at 270.51 118.11 0)
			(effects
				(font
					(size 1.27 1.27)
				)
				(hide yes)
			)
		)
		(property "MPN" "C0402C470J5GACTU"
			(at 288.29 97.79 0)
			(effects
				(font
					(size 1.27 1.27)
					(thickness 0.15)
				)
				(justify left bottom)
				(hide yes)
			)
		)
		(property "Manufacturer" "KEMET"
			(at 290.83 97.79 0)
			(effects
				(font
					(size 1.27 1.27)
					(thickness 0.15)
				)
				(justify left bottom)
				(hide yes)
			)
		)
		(property "License" "Apache-2.0"
			(at 293.37 97.79 0)
			(effects
				(font
					(size 1.27 1.27)
					(thickness 0.15)
				)
				(justify left bottom)
				(hide yes)
			)
		)
		(property "Author" "Antmicro"
			(at 295.91 97.79 0)
			(effects
				(font
					(size 1.27 1.27)
					(thickness 0.15)
				)
				(justify left bottom)
				(hide yes)
			)
		)
		(property "Val" "47p"
			(at 267.97 116.8336 90)
			(effects
				(font
					(size 1.27 1.27)
					(thickness 0.15)
				)
				(justify left)
			)
		)
		(property "Voltage" ""
			(at 298.45 97.79 0)
			(effects
				(font
					(size 1.27 1.27)
				)
				(justify left bottom)
				(hide yes)
			)
		)
		(property "Dielectric" "C0G"
			(at 300.99 97.79 0)
			(effects
				(font
					(size 1.27 1.27)
				)
				(justify left bottom)
				(hide yes)
			)
		)
		(pin "2"
		)
		(pin "1"
		)
		(instances
			(project "usb_debug_pd"
				(path ""
					(reference "C?")
					(unit 1)
				)
			)
			(project "jetson-agx-thor-baseboard"
				(path ""
					(reference "C149")
					(unit 1)
				)
			)
		)
	)
	(symbol
		(lib_id "antmicropower:GND")
		(at 73.66 72.39 0)
		(mirror y)
		(unit 1)
		(exclude_from_sim no)
		(in_bom yes)
		(on_board yes)
		(dnp no)
		(property "Reference" "#PWR0232"
			(at 73.66 78.74 0)
			(effects
				(font
					(size 1.27 1.27)
				)
				(justify left bottom)
				(hide yes)
			)
		)
		(property "Value" "GND"
			(at 73.66 76.2 0)
			(effects
				(font
					(size 1.27 1.27)
					(thickness 0.15)
				)
			)
		)
		(property "Footprint" ""
			(at 64.77 80.01 0)
			(effects
				(font
					(size 1.27 1.27)
					(thickness 0.15)
				)
				(justify left bottom)
				(hide yes)
			)
		)
		(property "Datasheet" ""
			(at 64.77 85.09 0)
			(effects
				(font
					(size 1.27 1.27)
					(thickness 0.15)
				)
				(justify left bottom)
				(hide yes)
			)
		)
		(property "Description" ""
			(at 73.66 72.39 0)
			(effects
				(font
					(size 1.27 1.27)
				)
				(hide yes)
			)
		)
		(property "Author" "Antmicro"
			(at 64.77 80.01 0)
			(effects
				(font
					(size 1.27 1.27)
					(thickness 0.15)
				)
				(justify left bottom)
				(hide yes)
			)
		)
		(property "License" "Apache-2.0"
			(at 64.77 82.55 0)
			(effects
				(font
					(size 1.27 1.27)
					(thickness 0.15)
				)
				(justify left bottom)
				(hide yes)
			)
		)
		(pin "1"
		)
		(instances
			(project "usb_debug_pd"
				(path ""
					(reference "#PWR?")
					(unit 1)
				)
			)
			(project "jetson-agx-thor-baseboard"
				(path ""
					(reference "#PWR0232")
					(unit 1)
				)
			)
		)
	)
	(symbol
		(lib_id "antmicropower:GND")
		(at 45.72 106.68 0)
		(mirror y)
		(unit 1)
		(exclude_from_sim no)
		(in_bom yes)
		(on_board yes)
		(dnp no)
		(property "Reference" "#PWR0487"
			(at 45.72 113.03 0)
			(effects
				(font
					(size 1.27 1.27)
				)
				(justify left bottom)
				(hide yes)
			)
		)
		(property "Value" "GND"
			(at 45.72 110.49 0)
			(effects
				(font
					(size 1.27 1.27)
					(thickness 0.15)
				)
			)
		)
		(property "Footprint" ""
			(at 36.83 114.3 0)
			(effects
				(font
					(size 1.27 1.27)
					(thickness 0.15)
				)
				(justify left bottom)
				(hide yes)
			)
		)
		(property "Datasheet" ""
			(at 36.83 119.38 0)
			(effects
				(font
					(size 1.27 1.27)
					(thickness 0.15)
				)
				(justify left bottom)
				(hide yes)
			)
		)
		(property "Description" ""
			(at 45.72 106.68 0)
			(effects
				(font
					(size 1.27 1.27)
				)
				(hide yes)
			)
		)
		(property "Author" "Antmicro"
			(at 36.83 114.3 0)
			(effects
				(font
					(size 1.27 1.27)
					(thickness 0.15)
				)
				(justify left bottom)
				(hide yes)
			)
		)
		(property "License" "Apache-2.0"
			(at 36.83 116.84 0)
			(effects
				(font
					(size 1.27 1.27)
					(thickness 0.15)
				)
				(justify left bottom)
				(hide yes)
			)
		)
		(pin "1"
		)
		(instances
			(project "usb_debug_pd"
				(path ""
					(reference "#PWR?")
					(unit 1)
				)
			)
			(project "jetson-agx-thor-baseboard"
				(path ""
					(reference "#PWR0487")
					(unit 1)
				)
			)
		)
	)
	(symbol
		(lib_id "antmicropower:GND")
		(at 293.37 102.87 0)
		(mirror y)
		(unit 1)
		(exclude_from_sim no)
		(in_bom yes)
		(on_board yes)
		(dnp no)
		(property "Reference" "#PWR0276"
			(at 293.37 109.22 0)
			(effects
				(font
					(size 1.27 1.27)
				)
				(justify left bottom)
				(hide yes)
			)
		)
		(property "Value" "GND"
			(at 293.37 106.68 0)
			(effects
				(font
					(size 1.27 1.27)
					(thickness 0.15)
				)
			)
		)
		(property "Footprint" ""
			(at 284.48 110.49 0)
			(effects
				(font
					(size 1.27 1.27)
					(thickness 0.15)
				)
				(justify left bottom)
				(hide yes)
			)
		)
		(property "Datasheet" ""
			(at 284.48 115.57 0)
			(effects
				(font
					(size 1.27 1.27)
					(thickness 0.15)
				)
				(justify left bottom)
				(hide yes)
			)
		)
		(property "Description" ""
			(at 293.37 102.87 0)
			(effects
				(font
					(size 1.27 1.27)
				)
				(hide yes)
			)
		)
		(property "Author" "Antmicro"
			(at 284.48 110.49 0)
			(effects
				(font
					(size 1.27 1.27)
					(thickness 0.15)
				)
				(justify left bottom)
				(hide yes)
			)
		)
		(property "License" "Apache-2.0"
			(at 284.48 113.03 0)
			(effects
				(font
					(size 1.27 1.27)
					(thickness 0.15)
				)
				(justify left bottom)
				(hide yes)
			)
		)
		(pin "1"
		)
		(instances
			(project "usb_debug_pd"
				(path ""
					(reference "#PWR?")
					(unit 1)
				)
			)
			(project "jetson-agx-thor-baseboard"
				(path ""
					(reference "#PWR0276")
					(unit 1)
				)
			)
		)
	)
	(symbol
		(lib_id "antmicropower:GND")
		(at 161.29 198.12 0)
		(mirror y)
		(unit 1)
		(exclude_from_sim no)
		(in_bom yes)
		(on_board yes)
		(dnp no)
		(property "Reference" "#PWR0222"
			(at 161.29 204.47 0)
			(effects
				(font
					(size 1.27 1.27)
				)
				(justify left bottom)
				(hide yes)
			)
		)
		(property "Value" "GND"
			(at 161.29 201.93 0)
			(effects
				(font
					(size 1.27 1.27)
					(thickness 0.15)
				)
			)
		)
		(property "Footprint" ""
			(at 152.4 205.74 0)
			(effects
				(font
					(size 1.27 1.27)
					(thickness 0.15)
				)
				(justify left bottom)
				(hide yes)
			)
		)
		(property "Datasheet" ""
			(at 152.4 210.82 0)
			(effects
				(font
					(size 1.27 1.27)
					(thickness 0.15)
				)
				(justify left bottom)
				(hide yes)
			)
		)
		(property "Description" ""
			(at 161.29 198.12 0)
			(effects
				(font
					(size 1.27 1.27)
				)
				(hide yes)
			)
		)
		(property "Author" "Antmicro"
			(at 152.4 205.74 0)
			(effects
				(font
					(size 1.27 1.27)
					(thickness 0.15)
				)
				(justify left bottom)
				(hide yes)
			)
		)
		(property "License" "Apache-2.0"
			(at 152.4 208.28 0)
			(effects
				(font
					(size 1.27 1.27)
					(thickness 0.15)
				)
				(justify left bottom)
				(hide yes)
			)
		)
		(pin "1"
		)
		(instances
			(project "usb_debug_pd"
				(path ""
					(reference "#PWR?")
					(unit 1)
				)
			)
			(project "jetson-agx-thor-baseboard"
				(path ""
					(reference "#PWR0222")
					(unit 1)
				)
			)
		)
	)
	(symbol
		(lib_id "antmicropower:+5V")
		(at 250.19 25.4 0)
		(unit 1)
		(exclude_from_sim no)
		(in_bom yes)
		(on_board yes)
		(dnp no)
		(property "Reference" "#PWR0264"
			(at 250.19 29.21 0)
			(effects
				(font
					(size 1.27 1.27)
				)
				(justify left bottom)
				(hide yes)
			)
		)
		(property "Value" "+5V"
			(at 247.65 21.59 0)
			(effects
				(font
					(size 1.27 1.27)
					(thickness 0.15)
				)
				(justify left)
			)
		)
		(property "Footprint" ""
			(at 265.43 33.02 0)
			(effects
				(font
					(size 1.27 1.27)
					(thickness 0.15)
				)
				(justify left bottom)
				(hide yes)
			)
		)
		(property "Datasheet" ""
			(at 265.43 35.56 0)
			(effects
				(font
					(size 1.27 1.27)
					(thickness 0.15)
				)
				(justify left bottom)
				(hide yes)
			)
		)
		(property "Description" ""
			(at 250.19 25.4 0)
			(effects
				(font
					(size 1.27 1.27)
				)
				(hide yes)
			)
		)
		(property "Author" "Antmicro"
			(at 265.43 33.02 0)
			(effects
				(font
					(size 1.27 1.27)
					(thickness 0.15)
				)
				(justify left bottom)
				(hide yes)
			)
		)
		(property "License" "Apache-2.0"
			(at 265.43 35.56 0)
			(effects
				(font
					(size 1.27 1.27)
					(thickness 0.15)
				)
				(justify left bottom)
				(hide yes)
			)
		)
		(pin "1"
		)
		(instances
			(project "usb_debug_pd"
				(path ""
					(reference "#PWR?")
					(unit 1)
				)
			)
			(project "jetson-agx-thor-baseboard"
				(path ""
					(reference "#PWR0264")
					(unit 1)
				)
			)
		)
	)
	(symbol
		(lib_id "antmicroCapacitors0402:C_10u_0402")
		(at 153.67 196.85 90)
		(unit 1)
		(exclude_from_sim no)
		(in_bom yes)
		(on_board yes)
		(dnp no)
		(property "Reference" "C120"
			(at 154.305 192.405 90)
			(effects
				(font
					(size 1.27 1.27)
					(thickness 0.15)
				)
				(justify right)
			)
		)
		(property "Value" "C_10u_0402"
			(at 163.83 176.53 0)
			(effects
				(font
					(size 1.27 1.27)
					(thickness 0.15)
				)
				(justify left bottom)
				(hide yes)
			)
		)
		(property "Footprint" "antmicro-footprints:C_0402_1005Metric"
			(at 166.37 176.53 0)
			(effects
				(font
					(size 1.27 1.27)
					(thickness 0.15)
				)
				(justify left bottom)
				(hide yes)
			)
		)
		(property "Datasheet" "https://www.yageo.com/en/Chart/Download/pdf/CC0402MRX5R5BB106"
			(at 168.91 176.53 0)
			(effects
				(font
					(size 1.27 1.27)
					(thickness 0.15)
				)
				(justify left bottom)
				(hide yes)
			)
		)
		(property "Description" "SMD Multilayer Ceramic Capacitor, 10 µF, 6.3 V, 0402 [1005 Metric], ± 20%, X5R, CC Series"
			(at 153.67 196.85 0)
			(effects
				(font
					(size 1.27 1.27)
				)
				(hide yes)
			)
		)
		(property "MPN" "CC0402MRX5R5BB106"
			(at 171.45 176.53 0)
			(effects
				(font
					(size 1.27 1.27)
					(thickness 0.15)
				)
				(justify left bottom)
				(hide yes)
			)
		)
		(property "Manufacturer" "YAGEO"
			(at 173.99 176.53 0)
			(effects
				(font
					(size 1.27 1.27)
					(thickness 0.15)
				)
				(justify left bottom)
				(hide yes)
			)
		)
		(property "License" "Apache-2.0"
			(at 176.53 176.53 0)
			(effects
				(font
					(size 1.27 1.27)
					(thickness 0.15)
				)
				(justify left bottom)
				(hide yes)
			)
		)
		(property "Author" "Antmicro"
			(at 179.07 176.53 0)
			(effects
				(font
					(size 1.27 1.27)
					(thickness 0.15)
				)
				(justify left bottom)
				(hide yes)
			)
		)
		(property "Val" "10u"
			(at 154.305 196.215 90)
			(effects
				(font
					(size 1.27 1.27)
					(thickness 0.15)
				)
				(justify right)
			)
		)
		(property "Voltage" ""
			(at 181.61 176.53 0)
			(effects
				(font
					(size 1.27 1.27)
				)
				(justify left bottom)
				(hide yes)
			)
		)
		(property "Dielectric" ""
			(at 184.15 176.53 0)
			(effects
				(font
					(size 1.27 1.27)
				)
				(justify left bottom)
				(hide yes)
			)
		)
		(pin "1"
		)
		(pin "2"
		)
		(instances
			(project "usb_debug_pd"
				(path ""
					(reference "C?")
					(unit 1)
				)
			)
			(project "jetson-agx-thor-baseboard"
				(path ""
					(reference "C120")
					(unit 1)
				)
			)
		)
	)
	(symbol
		(lib_id "antmicroResistors0402:R_10k_0402")
		(at 274.32 31.75 90)
		(unit 1)
		(exclude_from_sim no)
		(in_bom yes)
		(on_board yes)
		(dnp no)
		(property "Reference" "R150"
			(at 275.59 27.94 90)
			(effects
				(font
					(size 1.27 1.27)
				)
				(justify right)
			)
		)
		(property "Value" "R_10k_0402"
			(at 287.02 11.43 0)
			(effects
				(font
					(size 1.27 1.27)
					(thickness 0.15)
				)
				(justify left bottom)
				(hide yes)
			)
		)
		(property "Footprint" "antmicro-footprints:R_0402_1005Metric"
			(at 289.56 11.43 0)
			(effects
				(font
					(size 1.27 1.27)
					(thickness 0.15)
				)
				(justify left bottom)
				(hide yes)
			)
		)
		(property "Datasheet" "https://www.bourns.com/docs/product-datasheets/cr.pdf"
			(at 292.1 11.43 0)
			(effects
				(font
					(size 1.27 1.27)
					(thickness 0.15)
				)
				(justify left bottom)
				(hide yes)
			)
		)
		(property "Description" "SMD Chip Resistor, 10 kohm, ± 1%, 62.5 mW, 0402 [1005 Metric], Thick Film, General Purpose"
			(at 274.32 31.75 0)
			(effects
				(font
					(size 1.27 1.27)
				)
				(hide yes)
			)
		)
		(property "Manufacturer" "Bourns"
			(at 297.18 11.43 0)
			(effects
				(font
					(size 1.27 1.27)
					(thickness 0.15)
				)
				(justify left bottom)
				(hide yes)
			)
		)
		(property "MPN" "CR0402-FX-1002GLF"
			(at 294.64 11.43 0)
			(effects
				(font
					(size 1.27 1.27)
					(thickness 0.15)
				)
				(justify left bottom)
				(hide yes)
			)
		)
		(property "Val" "10k"
			(at 275.59 30.48 90)
			(effects
				(font
					(size 1.27 1.27)
					(thickness 0.15)
				)
				(justify right)
			)
		)
		(property "License" "Apache-2.0"
			(at 299.72 11.43 0)
			(effects
				(font
					(size 1.27 1.27)
					(thickness 0.15)
				)
				(justify left bottom)
				(hide yes)
			)
		)
		(property "Author" "Antmicro"
			(at 302.26 11.43 0)
			(effects
				(font
					(size 1.27 1.27)
					(thickness 0.15)
				)
				(justify left bottom)
				(hide yes)
			)
		)
		(property "Tolerance" "1%"
			(at 284.48 11.43 0)
			(effects
				(font
					(size 1.27 1.27)
				)
				(justify left bottom)
				(hide yes)
			)
		)
		(pin "1"
		)
		(pin "2"
		)
		(instances
			(project "usb_debug_pd"
				(path ""
					(reference "R?")
					(unit 1)
				)
			)
			(project "jetson-agx-thor-baseboard"
				(path ""
					(reference "R150")
					(unit 1)
				)
			)
		)
	)
	(symbol
		(lib_id "antmicropower:GND")
		(at 50.8 120.65 0)
		(unit 1)
		(exclude_from_sim no)
		(in_bom yes)
		(on_board yes)
		(dnp no)
		(property "Reference" "#PWR0230"
			(at 50.8 127 0)
			(effects
				(font
					(size 1.27 1.27)
				)
				(justify left bottom)
				(hide yes)
			)
		)
		(property "Value" "GND"
			(at 50.8 124.46 0)
			(effects
				(font
					(size 1.27 1.27)
					(thickness 0.15)
				)
			)
		)
		(property "Footprint" ""
			(at 59.69 128.27 0)
			(effects
				(font
					(size 1.27 1.27)
					(thickness 0.15)
				)
				(justify left bottom)
				(hide yes)
			)
		)
		(property "Datasheet" ""
			(at 59.69 133.35 0)
			(effects
				(font
					(size 1.27 1.27)
					(thickness 0.15)
				)
				(justify left bottom)
				(hide yes)
			)
		)
		(property "Description" ""
			(at 50.8 120.65 0)
			(effects
				(font
					(size 1.27 1.27)
				)
				(hide yes)
			)
		)
		(property "Author" "Antmicro"
			(at 59.69 128.27 0)
			(effects
				(font
					(size 1.27 1.27)
					(thickness 0.15)
				)
				(justify left bottom)
				(hide yes)
			)
		)
		(property "License" "Apache-2.0"
			(at 59.69 130.81 0)
			(effects
				(font
					(size 1.27 1.27)
					(thickness 0.15)
				)
				(justify left bottom)
				(hide yes)
			)
		)
		(pin "1"
		)
		(instances
			(project "usb_debug_pd"
				(path ""
					(reference "#PWR?")
					(unit 1)
				)
			)
			(project "jetson-agx-thor-baseboard"
				(path ""
					(reference "#PWR0230")
					(unit 1)
				)
			)
		)
	)
	(symbol
		(lib_id "antmicroResistors0402:R_0R_0402")
		(at 92.71 205.74 0)
		(unit 1)
		(exclude_from_sim no)
		(in_bom yes)
		(on_board yes)
		(dnp no)
		(property "Reference" "R383"
			(at 99.822 204.47 0)
			(effects
				(font
					(size 1.27 1.27)
					(thickness 0.15)
				)
			)
		)
		(property "Value" "R_0R_0402"
			(at 113.03 218.44 0)
			(effects
				(font
					(size 1.27 1.27)
					(thickness 0.15)
				)
				(justify left bottom)
				(hide yes)
			)
		)
		(property "Footprint" "antmicro-footprints:R_0402_1005Metric"
			(at 113.03 220.98 0)
			(effects
				(font
					(size 1.27 1.27)
					(thickness 0.15)
				)
				(justify left bottom)
				(hide yes)
			)
		)
		(property "Datasheet" "https://industrial.panasonic.com/cdbs/www-data/pdf/RDA0000/AOA0000C301.pdf"
			(at 113.03 223.52 0)
			(effects
				(font
					(size 1.27 1.27)
					(thickness 0.15)
				)
				(justify left bottom)
				(hide yes)
			)
		)
		(property "Description" "SMD Chip Resistor, Jumper, 0 ohm, 100 mW, 0402 [1005 Metric], Thick Film, General Purpose"
			(at 113.03 238.76 0)
			(effects
				(font
					(size 1.27 1.27)
				)
				(justify left bottom)
				(hide yes)
			)
		)
		(property "MPN" "ERJ2GE0R00X"
			(at 113.03 226.06 0)
			(effects
				(font
					(size 1.27 1.27)
					(thickness 0.15)
				)
				(justify left bottom)
				(hide yes)
			)
		)
		(property "Manufacturer" "Panasonic"
			(at 113.03 228.6 0)
			(effects
				(font
					(size 1.27 1.27)
					(thickness 0.15)
				)
				(justify left bottom)
				(hide yes)
			)
		)
		(property "License" "Apache-2.0"
			(at 113.03 231.14 0)
			(effects
				(font
					(size 1.27 1.27)
					(thickness 0.15)
				)
				(justify left bottom)
				(hide yes)
			)
		)
		(property "Author" "Antmicro"
			(at 113.03 233.68 0)
			(effects
				(font
					(size 1.27 1.27)
					(thickness 0.15)
				)
				(justify left bottom)
				(hide yes)
			)
		)
		(property "Val" "0R"
			(at 91.948 204.47 0)
			(effects
				(font
					(size 1.27 1.27)
					(thickness 0.15)
				)
			)
		)
		(property "Tolerance" "~"
			(at 113.03 215.9 0)
			(effects
				(font
					(size 1.27 1.27)
				)
				(justify left bottom)
				(hide yes)
			)
		)
		(property "Current" "1A"
			(at 113.03 236.22 0)
			(effects
				(font
					(size 1.27 1.27)
					(thickness 0.15)
				)
				(justify left bottom)
				(hide yes)
			)
		)
		(pin "2"
		)
		(pin "1"
		)
		(instances
			(project "jetson-agx-thor-baseboard"
				(path ""
					(reference "R383")
					(unit 1)
				)
			)
		)
	)
	(symbol
		(lib_id "antmicroResistors0402:R_0R_0402")
		(at 158.75 207.01 0)
		(unit 1)
		(exclude_from_sim no)
		(in_bom yes)
		(on_board yes)
		(dnp no)
		(property "Reference" "R93"
			(at 163.83 206.375 0)
			(effects
				(font
					(size 1.27 1.27)
				)
				(justify left bottom)
			)
		)
		(property "Value" "R_0R_0402"
			(at 179.07 219.71 0)
			(effects
				(font
					(size 1.27 1.27)
					(thickness 0.15)
				)
				(justify left bottom)
				(hide yes)
			)
		)
		(property "Footprint" "antmicro-footprints:R_0402_1005Metric"
			(at 179.07 222.25 0)
			(effects
				(font
					(size 1.27 1.27)
					(thickness 0.15)
				)
				(justify left bottom)
				(hide yes)
			)
		)
		(property "Datasheet" "https://industrial.panasonic.com/cdbs/www-data/pdf/RDA0000/AOA0000C301.pdf"
			(at 179.07 224.79 0)
			(effects
				(font
					(size 1.27 1.27)
					(thickness 0.15)
				)
				(justify left bottom)
				(hide yes)
			)
		)
		(property "Description" "SMD Chip Resistor, Jumper, 0 ohm, 100 mW, 0402 [1005 Metric], Thick Film, General Purpose"
			(at 158.75 207.01 0)
			(effects
				(font
					(size 1.27 1.27)
				)
				(hide yes)
			)
		)
		(property "Manufacturer" "Panasonic"
			(at 179.07 229.87 0)
			(effects
				(font
					(size 1.27 1.27)
					(thickness 0.15)
				)
				(justify left bottom)
				(hide yes)
			)
		)
		(property "MPN" "ERJ2GE0R00X"
			(at 179.07 227.33 0)
			(effects
				(font
					(size 1.27 1.27)
					(thickness 0.15)
				)
				(justify left bottom)
				(hide yes)
			)
		)
		(property "Val" "0R"
			(at 156.21 206.375 0)
			(effects
				(font
					(size 1.27 1.27)
					(thickness 0.15)
				)
				(justify left bottom)
			)
		)
		(property "License" "Apache-2.0"
			(at 179.07 232.41 0)
			(effects
				(font
					(size 1.27 1.27)
					(thickness 0.15)
				)
				(justify left bottom)
				(hide yes)
			)
		)
		(property "Author" "Antmicro"
			(at 179.07 234.95 0)
			(effects
				(font
					(size 1.27 1.27)
					(thickness 0.15)
				)
				(justify left bottom)
				(hide yes)
			)
		)
		(property "Tolerance" "~"
			(at 179.07 217.17 0)
			(effects
				(font
					(size 1.27 1.27)
				)
				(justify left bottom)
				(hide yes)
			)
		)
		(property "Current" "1A"
			(at 179.07 237.49 0)
			(effects
				(font
					(size 1.27 1.27)
					(thickness 0.15)
				)
				(justify left bottom)
				(hide yes)
			)
		)
		(pin "1"
		)
		(pin "2"
		)
		(instances
			(project "usb_debug_pd"
				(path ""
					(reference "R?")
					(unit 1)
				)
			)
			(project "jetson-agx-thor-baseboard"
				(path ""
					(reference "R93")
					(unit 1)
				)
			)
		)
	)
	(symbol
		(lib_id "antmicroLEDIndicationDiscrete:LED_G_0603_LTST-C190GKT")
		(at 120.65 107.95 90)
		(unit 1)
		(exclude_from_sim no)
		(in_bom yes)
		(on_board yes)
		(dnp no)
		(property "Reference" "D21"
			(at 122.555 104.14 90)
			(effects
				(font
					(size 1.27 1.27)
				)
				(justify right)
			)
		)
		(property "Value" "LED_G_0603_LTST-C190GKT"
			(at 128.27 85.09 0)
			(effects
				(font
					(size 1.27 1.27)
					(thickness 0.15)
				)
				(justify left bottom)
				(hide yes)
			)
		)
		(property "Footprint" "antmicro-footprints:LED_0603_1608Metric_G"
			(at 130.81 85.09 0)
			(effects
				(font
					(size 1.27 1.27)
					(thickness 0.15)
				)
				(justify left bottom)
				(hide yes)
			)
		)
		(property "Datasheet" "https://media.digikey.com/pdf/Data%20Sheets/Lite-On%20PDFs/LTST-C190GKT.pdf"
			(at 133.35 85.09 0)
			(effects
				(font
					(size 1.27 1.27)
					(thickness 0.15)
				)
				(justify left bottom)
				(hide yes)
			)
		)
		(property "Description" "LED, Green, SMD, 0603, 20 mA, 2.1 V, 569 nm"
			(at 120.65 107.95 0)
			(effects
				(font
					(size 1.27 1.27)
				)
				(hide yes)
			)
		)
		(property "MPN" "LTST-C190GKT"
			(at 135.89 85.09 0)
			(effects
				(font
					(size 1.27 1.27)
					(thickness 0.15)
				)
				(justify left bottom)
				(hide yes)
			)
		)
		(property "Manufacturer" "Lite-On"
			(at 138.43 85.09 0)
			(effects
				(font
					(size 1.27 1.27)
					(thickness 0.15)
				)
				(justify left bottom)
				(hide yes)
			)
		)
		(property "Author" "Antmicro"
			(at 140.97 85.09 0)
			(effects
				(font
					(size 1.27 1.27)
					(thickness 0.15)
				)
				(justify left bottom)
				(hide yes)
			)
		)
		(property "License" "Apache-2.0"
			(at 143.51 85.09 0)
			(effects
				(font
					(size 1.27 1.27)
					(thickness 0.15)
				)
				(justify left bottom)
				(hide yes)
			)
		)
		(property "Color" "Green"
			(at 122.555 106.68 90)
			(effects
				(font
					(size 1.27 1.27)
				)
				(justify right)
			)
		)
		(pin "1"
		)
		(pin "2"
		)
		(instances
			(project "usb_debug_pd"
				(path ""
					(reference "D?")
					(unit 1)
				)
			)
			(project "jetson-agx-thor-baseboard"
				(path ""
					(reference "D21")
					(unit 1)
				)
			)
		)
	)
	(symbol
		(lib_id "antmicroResistors0402:R_2k2_0402")
		(at 306.07 40.64 90)
		(unit 1)
		(exclude_from_sim no)
		(in_bom yes)
		(on_board yes)
		(dnp no)
		(property "Reference" "R153"
			(at 307.34 36.83 90)
			(effects
				(font
					(size 1.27 1.27)
				)
				(justify right)
			)
		)
		(property "Value" "R_2k2_0402"
			(at 318.77 20.32 0)
			(effects
				(font
					(size 1.27 1.27)
					(thickness 0.15)
				)
				(justify left bottom)
				(hide yes)
			)
		)
		(property "Footprint" "antmicro-footprints:R_0402_1005Metric"
			(at 321.31 20.32 0)
			(effects
				(font
					(size 1.27 1.27)
					(thickness 0.15)
				)
				(justify left bottom)
				(hide yes)
			)
		)
		(property "Datasheet" "https://www.bourns.com/docs/product-datasheets/cr.pdf"
			(at 323.85 20.32 0)
			(effects
				(font
					(size 1.27 1.27)
					(thickness 0.15)
				)
				(justify left bottom)
				(hide yes)
			)
		)
		(property "Description" "SMD Chip Resistor, 2.2 kohm, ± 1%, 62.5 mW, 0402 [1005 Metric], Thick Film, General Purpose"
			(at 306.07 40.64 0)
			(effects
				(font
					(size 1.27 1.27)
				)
				(hide yes)
			)
		)
		(property "Manufacturer" "Bourns"
			(at 328.93 20.32 0)
			(effects
				(font
					(size 1.27 1.27)
					(thickness 0.15)
				)
				(justify left bottom)
				(hide yes)
			)
		)
		(property "MPN" "CR0402-FX-2201GLF"
			(at 326.39 20.32 0)
			(effects
				(font
					(size 1.27 1.27)
					(thickness 0.15)
				)
				(justify left bottom)
				(hide yes)
			)
		)
		(property "Val" "2k2"
			(at 307.34 39.37 90)
			(effects
				(font
					(size 1.27 1.27)
					(thickness 0.15)
				)
				(justify right)
			)
		)
		(property "License" "Apache-2.0"
			(at 331.47 20.32 0)
			(effects
				(font
					(size 1.27 1.27)
					(thickness 0.15)
				)
				(justify left bottom)
				(hide yes)
			)
		)
		(property "Author" "Antmicro"
			(at 334.01 20.32 0)
			(effects
				(font
					(size 1.27 1.27)
					(thickness 0.15)
				)
				(justify left bottom)
				(hide yes)
			)
		)
		(property "Tolerance" "1%"
			(at 316.23 20.32 0)
			(effects
				(font
					(size 1.27 1.27)
				)
				(justify left bottom)
				(hide yes)
			)
		)
		(pin "1"
		)
		(pin "2"
		)
		(instances
			(project "usb_debug_pd"
				(path ""
					(reference "R?")
					(unit 1)
				)
			)
			(project "jetson-agx-thor-baseboard"
				(path ""
					(reference "R153")
					(unit 1)
				)
			)
		)
	)
	(symbol
		(lib_id "antmicropower:GND")
		(at 179.07 262.89 0)
		(mirror y)
		(unit 1)
		(exclude_from_sim no)
		(in_bom yes)
		(on_board yes)
		(dnp no)
		(property "Reference" "#PWR0224"
			(at 179.07 269.24 0)
			(effects
				(font
					(size 1.27 1.27)
				)
				(justify left bottom)
				(hide yes)
			)
		)
		(property "Value" "GND"
			(at 179.07 266.7 0)
			(effects
				(font
					(size 1.27 1.27)
					(thickness 0.15)
				)
			)
		)
		(property "Footprint" ""
			(at 170.18 270.51 0)
			(effects
				(font
					(size 1.27 1.27)
					(thickness 0.15)
				)
				(justify left bottom)
				(hide yes)
			)
		)
		(property "Datasheet" ""
			(at 170.18 275.59 0)
			(effects
				(font
					(size 1.27 1.27)
					(thickness 0.15)
				)
				(justify left bottom)
				(hide yes)
			)
		)
		(property "Description" ""
			(at 179.07 262.89 0)
			(effects
				(font
					(size 1.27 1.27)
				)
				(hide yes)
			)
		)
		(property "Author" "Antmicro"
			(at 170.18 270.51 0)
			(effects
				(font
					(size 1.27 1.27)
					(thickness 0.15)
				)
				(justify left bottom)
				(hide yes)
			)
		)
		(property "License" "Apache-2.0"
			(at 170.18 273.05 0)
			(effects
				(font
					(size 1.27 1.27)
					(thickness 0.15)
				)
				(justify left bottom)
				(hide yes)
			)
		)
		(pin "1"
		)
		(instances
			(project "usb_debug_pd"
				(path ""
					(reference "#PWR?")
					(unit 1)
				)
			)
			(project "jetson-agx-thor-baseboard"
				(path ""
					(reference "#PWR0224")
					(unit 1)
				)
			)
		)
	)
	(symbol
		(lib_id "antmicroCapacitors0402:C_100n_0402")
		(at 250.19 26.67 90)
		(mirror x)
		(unit 1)
		(exclude_from_sim no)
		(in_bom yes)
		(on_board yes)
		(dnp no)
		(fields_autoplaced yes)
		(property "Reference" "C148"
			(at 252.73 27.9463 90)
			(effects
				(font
					(size 1.27 1.27)
				)
				(justify right)
			)
		)
		(property "Value" "C_100n_0402"
			(at 260.35 46.99 0)
			(effects
				(font
					(size 1.27 1.27)
					(thickness 0.15)
				)
				(justify left bottom)
				(hide yes)
			)
		)
		(property "Footprint" "antmicro-footprints:C_0402_1005Metric"
			(at 262.89 46.99 0)
			(effects
				(font
					(size 1.27 1.27)
					(thickness 0.15)
				)
				(justify left bottom)
				(hide yes)
			)
		)
		(property "Datasheet" "https://www.murata.com/products/productdetail?partno=GRM155R61H104KE14%23"
			(at 265.43 46.99 0)
			(effects
				(font
					(size 1.27 1.27)
					(thickness 0.15)
				)
				(justify left bottom)
				(hide yes)
			)
		)
		(property "Description" "SMD Multilayer Ceramic Capacitor, 0.1 µF, 50 V, 0402 [1005 Metric], ± 10%, X5R, GRM Series"
			(at 250.19 26.67 0)
			(effects
				(font
					(size 1.27 1.27)
				)
				(hide yes)
			)
		)
		(property "Manufacturer" "Murata"
			(at 270.51 46.99 0)
			(effects
				(font
					(size 1.27 1.27)
					(thickness 0.15)
				)
				(justify left bottom)
				(hide yes)
			)
		)
		(property "MPN" "GRM155R61H104KE14D"
			(at 267.97 46.99 0)
			(effects
				(font
					(size 1.27 1.27)
					(thickness 0.15)
				)
				(justify left bottom)
				(hide yes)
			)
		)
		(property "Val" "100n"
			(at 252.73 30.4863 90)
			(effects
				(font
					(size 1.27 1.27)
					(thickness 0.15)
				)
				(justify right)
			)
		)
		(property "License" "Apache-2.0"
			(at 273.05 46.99 0)
			(effects
				(font
					(size 1.27 1.27)
					(thickness 0.15)
				)
				(justify left bottom)
				(hide yes)
			)
		)
		(property "Author" "Antmicro"
			(at 275.59 46.99 0)
			(effects
				(font
					(size 1.27 1.27)
					(thickness 0.15)
				)
				(justify left bottom)
				(hide yes)
			)
		)
		(property "Voltage" "50V"
			(at 278.13 46.99 0)
			(effects
				(font
					(size 1.27 1.27)
				)
				(justify left bottom)
				(hide yes)
			)
		)
		(property "Dielectric" "X5R"
			(at 280.67 46.99 0)
			(effects
				(font
					(size 1.27 1.27)
				)
				(justify left bottom)
				(hide yes)
			)
		)
		(pin "1"
		)
		(pin "2"
		)
		(instances
			(project "usb_debug_pd"
				(path ""
					(reference "C?")
					(unit 1)
				)
			)
			(project "jetson-agx-thor-baseboard"
				(path ""
					(reference "C148")
					(unit 1)
				)
			)
		)
	)
	(symbol
		(lib_id "antmicroResistors0402:R_10k_0402")
		(at 158.75 227.33 0)
		(unit 1)
		(exclude_from_sim no)
		(in_bom yes)
		(on_board yes)
		(dnp no)
		(property "Reference" "R96"
			(at 163.83 226.695 0)
			(effects
				(font
					(size 1.27 1.27)
				)
				(justify left bottom)
			)
		)
		(property "Value" "R_10k_0402"
			(at 179.07 240.03 0)
			(effects
				(font
					(size 1.27 1.27)
					(thickness 0.15)
				)
				(justify left bottom)
				(hide yes)
			)
		)
		(property "Footprint" "antmicro-footprints:R_0402_1005Metric"
			(at 179.07 242.57 0)
			(effects
				(font
					(size 1.27 1.27)
					(thickness 0.15)
				)
				(justify left bottom)
				(hide yes)
			)
		)
		(property "Datasheet" "https://www.bourns.com/docs/product-datasheets/cr.pdf"
			(at 179.07 245.11 0)
			(effects
				(font
					(size 1.27 1.27)
					(thickness 0.15)
				)
				(justify left bottom)
				(hide yes)
			)
		)
		(property "Description" "SMD Chip Resistor, 10 kohm, ± 1%, 62.5 mW, 0402 [1005 Metric], Thick Film, General Purpose"
			(at 158.75 227.33 0)
			(effects
				(font
					(size 1.27 1.27)
				)
				(hide yes)
			)
		)
		(property "Manufacturer" "Bourns"
			(at 179.07 250.19 0)
			(effects
				(font
					(size 1.27 1.27)
					(thickness 0.15)
				)
				(justify left bottom)
				(hide yes)
			)
		)
		(property "MPN" "CR0402-FX-1002GLF"
			(at 179.07 247.65 0)
			(effects
				(font
					(size 1.27 1.27)
					(thickness 0.15)
				)
				(justify left bottom)
				(hide yes)
			)
		)
		(property "Val" "10k"
			(at 155.575 226.695 0)
			(effects
				(font
					(size 1.27 1.27)
					(thickness 0.15)
				)
				(justify left bottom)
			)
		)
		(property "License" "Apache-2.0"
			(at 179.07 252.73 0)
			(effects
				(font
					(size 1.27 1.27)
					(thickness 0.15)
				)
				(justify left bottom)
				(hide yes)
			)
		)
		(property "Author" "Antmicro"
			(at 179.07 255.27 0)
			(effects
				(font
					(size 1.27 1.27)
					(thickness 0.15)
				)
				(justify left bottom)
				(hide yes)
			)
		)
		(property "Tolerance" "1%"
			(at 179.07 237.49 0)
			(effects
				(font
					(size 1.27 1.27)
				)
				(justify left bottom)
				(hide yes)
			)
		)
		(pin "1"
		)
		(pin "2"
		)
		(instances
			(project "usb_debug_pd"
				(path ""
					(reference "R?")
					(unit 1)
				)
			)
			(project "jetson-agx-thor-baseboard"
				(path ""
					(reference "R96")
					(unit 1)
				)
			)
		)
	)
	(symbol
		(lib_id "antmicropower:GND")
		(at 138.43 198.12 0)
		(mirror y)
		(unit 1)
		(exclude_from_sim no)
		(in_bom yes)
		(on_board yes)
		(dnp no)
		(property "Reference" "#PWR0214"
			(at 138.43 204.47 0)
			(effects
				(font
					(size 1.27 1.27)
				)
				(justify left bottom)
				(hide yes)
			)
		)
		(property "Value" "GND"
			(at 138.43 201.93 0)
			(effects
				(font
					(size 1.27 1.27)
					(thickness 0.15)
				)
			)
		)
		(property "Footprint" ""
			(at 129.54 205.74 0)
			(effects
				(font
					(size 1.27 1.27)
					(thickness 0.15)
				)
				(justify left bottom)
				(hide yes)
			)
		)
		(property "Datasheet" ""
			(at 129.54 210.82 0)
			(effects
				(font
					(size 1.27 1.27)
					(thickness 0.15)
				)
				(justify left bottom)
				(hide yes)
			)
		)
		(property "Description" ""
			(at 138.43 198.12 0)
			(effects
				(font
					(size 1.27 1.27)
				)
				(hide yes)
			)
		)
		(property "Author" "Antmicro"
			(at 129.54 205.74 0)
			(effects
				(font
					(size 1.27 1.27)
					(thickness 0.15)
				)
				(justify left bottom)
				(hide yes)
			)
		)
		(property "License" "Apache-2.0"
			(at 129.54 208.28 0)
			(effects
				(font
					(size 1.27 1.27)
					(thickness 0.15)
				)
				(justify left bottom)
				(hide yes)
			)
		)
		(pin "1"
		)
		(instances
			(project "usb_debug_pd"
				(path ""
					(reference "#PWR?")
					(unit 1)
				)
			)
			(project "jetson-agx-thor-baseboard"
				(path ""
					(reference "#PWR0214")
					(unit 1)
				)
			)
		)
	)
	(symbol
		(lib_id "antmicroCapacitors0402:C_47p_0402")
		(at 275.59 113.03 90)
		(mirror x)
		(unit 1)
		(exclude_from_sim no)
		(in_bom yes)
		(on_board yes)
		(dnp no)
		(fields_autoplaced yes)
		(property "Reference" "C150"
			(at 278.13 114.3063 90)
			(effects
				(font
					(size 1.27 1.27)
					(thickness 0.15)
				)
				(justify right)
			)
		)
		(property "Value" "C_47p_0402"
			(at 285.75 133.35 0)
			(effects
				(font
					(size 1.27 1.27)
					(thickness 0.15)
				)
				(justify left bottom)
				(hide yes)
			)
		)
		(property "Footprint" "antmicro-footprints:C_0402_1005Metric"
			(at 288.29 133.35 0)
			(effects
				(font
					(size 1.27 1.27)
					(thickness 0.15)
				)
				(justify left bottom)
				(hide yes)
			)
		)
		(property "Datasheet" "https://www.kemet.com/en/us/capacitors/product/C0402C470J5GACTU.html"
			(at 290.83 133.35 0)
			(effects
				(font
					(size 1.27 1.27)
					(thickness 0.15)
				)
				(justify left bottom)
				(hide yes)
			)
		)
		(property "Description" "SMD Multilayer Ceramic Capacitor, 47 pF, 50 V, 0402 [1005 Metric], ± 5%, C0G / NP0, C Series KEMET"
			(at 275.59 113.03 0)
			(effects
				(font
					(size 1.27 1.27)
				)
				(hide yes)
			)
		)
		(property "MPN" "C0402C470J5GACTU"
			(at 293.37 133.35 0)
			(effects
				(font
					(size 1.27 1.27)
					(thickness 0.15)
				)
				(justify left bottom)
				(hide yes)
			)
		)
		(property "Manufacturer" "KEMET"
			(at 295.91 133.35 0)
			(effects
				(font
					(size 1.27 1.27)
					(thickness 0.15)
				)
				(justify left bottom)
				(hide yes)
			)
		)
		(property "License" "Apache-2.0"
			(at 298.45 133.35 0)
			(effects
				(font
					(size 1.27 1.27)
					(thickness 0.15)
				)
				(justify left bottom)
				(hide yes)
			)
		)
		(property "Author" "Antmicro"
			(at 300.99 133.35 0)
			(effects
				(font
					(size 1.27 1.27)
					(thickness 0.15)
				)
				(justify left bottom)
				(hide yes)
			)
		)
		(property "Val" "47p"
			(at 278.13 116.8463 90)
			(effects
				(font
					(size 1.27 1.27)
					(thickness 0.15)
				)
				(justify right)
			)
		)
		(property "Voltage" ""
			(at 303.53 133.35 0)
			(effects
				(font
					(size 1.27 1.27)
				)
				(justify left bottom)
				(hide yes)
			)
		)
		(property "Dielectric" "C0G"
			(at 306.07 133.35 0)
			(effects
				(font
					(size 1.27 1.27)
				)
				(justify left bottom)
				(hide yes)
			)
		)
		(pin "2"
		)
		(pin "1"
		)
		(instances
			(project "usb_debug_pd"
				(path ""
					(reference "C?")
					(unit 1)
				)
			)
			(project "jetson-agx-thor-baseboard"
				(path ""
					(reference "C150")
					(unit 1)
				)
			)
		)
	)
	(symbol
		(lib_id "antmicroTestPoints:TP_0.75mm_SMD")
		(at 251.46 257.81 0)
		(unit 1)
		(exclude_from_sim no)
		(in_bom no)
		(on_board yes)
		(dnp no)
		(property "Reference" "TP14"
			(at 255.27 258.445 0)
			(effects
				(font
					(size 1.27 1.27)
				)
				(justify left bottom)
			)
		)
		(property "Value" "TP_0.75mm_SMD"
			(at 261.62 261.62 0)
			(effects
				(font
					(size 1.27 1.27)
					(thickness 0.15)
				)
				(justify left bottom)
				(hide yes)
			)
		)
		(property "Footprint" "antmicro-footprints:TP_SMD_0.75mm"
			(at 261.62 264.16 0)
			(effects
				(font
					(size 1.27 1.27)
					(thickness 0.15)
				)
				(justify left bottom)
				(hide yes)
			)
		)
		(property "Datasheet" ""
			(at 269.24 270.51 0)
			(effects
				(font
					(size 1.27 1.27)
					(thickness 0.15)
				)
				(justify left bottom)
				(hide yes)
			)
		)
		(property "Description" "SMT test point"
			(at 251.46 257.81 0)
			(effects
				(font
					(size 1.27 1.27)
				)
				(hide yes)
			)
		)
		(property "MPN" ""
			(at 262.255 269.24 0)
			(effects
				(font
					(size 1.27 1.27)
					(thickness 0.15)
				)
				(justify left bottom)
				(hide yes)
			)
		)
		(property "Manufacturer" ""
			(at 262.255 264.16 0)
			(effects
				(font
					(size 1.27 1.27)
					(thickness 0.15)
				)
				(justify left bottom)
				(hide yes)
			)
		)
		(property "Author" "Antmicro"
			(at 261.62 266.7 0)
			(effects
				(font
					(size 1.27 1.27)
					(thickness 0.15)
				)
				(justify left bottom)
				(hide yes)
			)
		)
		(property "License" "Apache-2.0"
			(at 261.62 269.24 0)
			(effects
				(font
					(size 1.27 1.27)
					(thickness 0.15)
				)
				(justify left bottom)
				(hide yes)
			)
		)
		(pin "1"
		)
		(instances
			(project "usb_debug_pd"
				(path ""
					(reference "TP?")
					(unit 1)
				)
			)
			(project "jetson-agx-thor-baseboard"
				(path ""
					(reference "TP14")
					(unit 1)
				)
			)
		)
	)
	(symbol
		(lib_id "antmicroCapacitors0402:C_10u_0402")
		(at 214.63 81.28 90)
		(unit 1)
		(exclude_from_sim no)
		(in_bom yes)
		(on_board yes)
		(dnp no)
		(fields_autoplaced yes)
		(property "Reference" "C147"
			(at 212.09 77.4636 90)
			(effects
				(font
					(size 1.27 1.27)
					(thickness 0.15)
				)
				(justify left)
			)
		)
		(property "Value" "C_10u_0402"
			(at 224.79 60.96 0)
			(effects
				(font
					(size 1.27 1.27)
					(thickness 0.15)
				)
				(justify left bottom)
				(hide yes)
			)
		)
		(property "Footprint" "antmicro-footprints:C_0402_1005Metric"
			(at 227.33 60.96 0)
			(effects
				(font
					(size 1.27 1.27)
					(thickness 0.15)
				)
				(justify left bottom)
				(hide yes)
			)
		)
		(property "Datasheet" "https://www.yageo.com/en/Chart/Download/pdf/CC0402MRX5R5BB106"
			(at 229.87 60.96 0)
			(effects
				(font
					(size 1.27 1.27)
					(thickness 0.15)
				)
				(justify left bottom)
				(hide yes)
			)
		)
		(property "Description" "SMD Multilayer Ceramic Capacitor, 10 µF, 6.3 V, 0402 [1005 Metric], ± 20%, X5R, CC Series"
			(at 214.63 81.28 0)
			(effects
				(font
					(size 1.27 1.27)
				)
				(hide yes)
			)
		)
		(property "MPN" "CC0402MRX5R5BB106"
			(at 232.41 60.96 0)
			(effects
				(font
					(size 1.27 1.27)
					(thickness 0.15)
				)
				(justify left bottom)
				(hide yes)
			)
		)
		(property "Manufacturer" "YAGEO"
			(at 234.95 60.96 0)
			(effects
				(font
					(size 1.27 1.27)
					(thickness 0.15)
				)
				(justify left bottom)
				(hide yes)
			)
		)
		(property "License" "Apache-2.0"
			(at 237.49 60.96 0)
			(effects
				(font
					(size 1.27 1.27)
					(thickness 0.15)
				)
				(justify left bottom)
				(hide yes)
			)
		)
		(property "Author" "Antmicro"
			(at 240.03 60.96 0)
			(effects
				(font
					(size 1.27 1.27)
					(thickness 0.15)
				)
				(justify left bottom)
				(hide yes)
			)
		)
		(property "Val" "10u"
			(at 212.09 80.0036 90)
			(effects
				(font
					(size 1.27 1.27)
					(thickness 0.15)
				)
				(justify left)
			)
		)
		(property "Voltage" ""
			(at 242.57 60.96 0)
			(effects
				(font
					(size 1.27 1.27)
				)
				(justify left bottom)
				(hide yes)
			)
		)
		(property "Dielectric" ""
			(at 245.11 60.96 0)
			(effects
				(font
					(size 1.27 1.27)
				)
				(justify left bottom)
				(hide yes)
			)
		)
		(pin "1"
		)
		(pin "2"
		)
		(instances
			(project "usb_debug_pd"
				(path ""
					(reference "C?")
					(unit 1)
				)
			)
			(project "jetson-agx-thor-baseboard"
				(path ""
					(reference "C147")
					(unit 1)
				)
			)
		)
	)
	(symbol
		(lib_id "antmicroLEDIndicationDiscrete:LED_G_0603_LTST-C190GKT")
		(at 113.03 107.95 90)
		(unit 1)
		(exclude_from_sim no)
		(in_bom yes)
		(on_board yes)
		(dnp no)
		(property "Reference" "D20"
			(at 109.22 104.14 90)
			(effects
				(font
					(size 1.27 1.27)
				)
				(justify left)
			)
		)
		(property "Value" "LED_G_0603_LTST-C190GKT"
			(at 120.65 85.09 0)
			(effects
				(font
					(size 1.27 1.27)
					(thickness 0.15)
				)
				(justify left bottom)
				(hide yes)
			)
		)
		(property "Footprint" "antmicro-footprints:LED_0603_1608Metric_G"
			(at 123.19 85.09 0)
			(effects
				(font
					(size 1.27 1.27)
					(thickness 0.15)
				)
				(justify left bottom)
				(hide yes)
			)
		)
		(property "Datasheet" "https://media.digikey.com/pdf/Data%20Sheets/Lite-On%20PDFs/LTST-C190GKT.pdf"
			(at 125.73 85.09 0)
			(effects
				(font
					(size 1.27 1.27)
					(thickness 0.15)
				)
				(justify left bottom)
				(hide yes)
			)
		)
		(property "Description" "LED, Green, SMD, 0603, 20 mA, 2.1 V, 569 nm"
			(at 113.03 107.95 0)
			(effects
				(font
					(size 1.27 1.27)
				)
				(hide yes)
			)
		)
		(property "MPN" "LTST-C190GKT"
			(at 128.27 85.09 0)
			(effects
				(font
					(size 1.27 1.27)
					(thickness 0.15)
				)
				(justify left bottom)
				(hide yes)
			)
		)
		(property "Manufacturer" "Lite-On"
			(at 130.81 85.09 0)
			(effects
				(font
					(size 1.27 1.27)
					(thickness 0.15)
				)
				(justify left bottom)
				(hide yes)
			)
		)
		(property "Author" "Antmicro"
			(at 133.35 85.09 0)
			(effects
				(font
					(size 1.27 1.27)
					(thickness 0.15)
				)
				(justify left bottom)
				(hide yes)
			)
		)
		(property "License" "Apache-2.0"
			(at 135.89 85.09 0)
			(effects
				(font
					(size 1.27 1.27)
					(thickness 0.15)
				)
				(justify left bottom)
				(hide yes)
			)
		)
		(property "Color" "Green"
			(at 109.22 106.68 90)
			(effects
				(font
					(size 1.27 1.27)
				)
				(justify left)
			)
		)
		(pin "1"
		)
		(pin "2"
		)
		(instances
			(project "usb_debug_pd"
				(path ""
					(reference "D?")
					(unit 1)
				)
			)
			(project "jetson-agx-thor-baseboard"
				(path ""
					(reference "D20")
					(unit 1)
				)
			)
		)
	)
	(symbol
		(lib_id "antmicroResistors0402:R_0R_0402")
		(at 157.48 99.06 0)
		(unit 1)
		(exclude_from_sim no)
		(in_bom yes)
		(on_board yes)
		(dnp no)
		(property "Reference" "R123"
			(at 157.48 98.425 0)
			(effects
				(font
					(size 1.27 1.27)
				)
				(justify right bottom)
			)
		)
		(property "Value" "R_0R_0402"
			(at 177.8 111.76 0)
			(effects
				(font
					(size 1.27 1.27)
					(thickness 0.15)
				)
				(justify left bottom)
				(hide yes)
			)
		)
		(property "Footprint" "antmicro-footprints:R_0402_1005Metric"
			(at 177.8 114.3 0)
			(effects
				(font
					(size 1.27 1.27)
					(thickness 0.15)
				)
				(justify left bottom)
				(hide yes)
			)
		)
		(property "Datasheet" "https://industrial.panasonic.com/cdbs/www-data/pdf/RDA0000/AOA0000C301.pdf"
			(at 177.8 116.84 0)
			(effects
				(font
					(size 1.27 1.27)
					(thickness 0.15)
				)
				(justify left bottom)
				(hide yes)
			)
		)
		(property "Description" "SMD Chip Resistor, Jumper, 0 ohm, 100 mW, 0402 [1005 Metric], Thick Film, General Purpose"
			(at 157.48 99.06 0)
			(effects
				(font
					(size 1.27 1.27)
				)
				(hide yes)
			)
		)
		(property "Manufacturer" "Panasonic"
			(at 177.8 121.92 0)
			(effects
				(font
					(size 1.27 1.27)
					(thickness 0.15)
				)
				(justify left bottom)
				(hide yes)
			)
		)
		(property "MPN" "ERJ2GE0R00X"
			(at 177.8 119.38 0)
			(effects
				(font
					(size 1.27 1.27)
					(thickness 0.15)
				)
				(justify left bottom)
				(hide yes)
			)
		)
		(property "Val" "0R"
			(at 165.1 98.425 0)
			(effects
				(font
					(size 1.27 1.27)
					(thickness 0.15)
				)
				(justify right bottom)
			)
		)
		(property "License" "Apache-2.0"
			(at 177.8 124.46 0)
			(effects
				(font
					(size 1.27 1.27)
					(thickness 0.15)
				)
				(justify left bottom)
				(hide yes)
			)
		)
		(property "Author" "Antmicro"
			(at 177.8 127 0)
			(effects
				(font
					(size 1.27 1.27)
					(thickness 0.15)
				)
				(justify left bottom)
				(hide yes)
			)
		)
		(property "Tolerance" "~"
			(at 177.8 109.22 0)
			(effects
				(font
					(size 1.27 1.27)
				)
				(justify left bottom)
				(hide yes)
			)
		)
		(property "Current" "1A"
			(at 177.8 129.54 0)
			(effects
				(font
					(size 1.27 1.27)
					(thickness 0.15)
				)
				(justify left bottom)
				(hide yes)
			)
		)
		(pin "1"
		)
		(pin "2"
		)
		(instances
			(project "usb_debug_pd"
				(path ""
					(reference "R?")
					(unit 1)
				)
			)
			(project "jetson-agx-thor-baseboard"
				(path ""
					(reference "R123")
					(unit 1)
				)
			)
		)
	)
	(symbol
		(lib_id "antmicroResistors0402:R_0R_0402")
		(at 55.88 237.49 0)
		(unit 1)
		(exclude_from_sim no)
		(in_bom no)
		(on_board yes)
		(dnp yes)
		(property "Reference" "R385"
			(at 62.992 236.22 0)
			(effects
				(font
					(size 1.27 1.27)
					(thickness 0.15)
				)
			)
		)
		(property "Value" "R_0R_0402"
			(at 76.2 250.19 0)
			(effects
				(font
					(size 1.27 1.27)
					(thickness 0.15)
				)
				(justify left bottom)
				(hide yes)
			)
		)
		(property "Footprint" "antmicro-footprints:R_0402_1005Metric"
			(at 76.2 252.73 0)
			(effects
				(font
					(size 1.27 1.27)
					(thickness 0.15)
				)
				(justify left bottom)
				(hide yes)
			)
		)
		(property "Datasheet" "https://industrial.panasonic.com/cdbs/www-data/pdf/RDA0000/AOA0000C301.pdf"
			(at 76.2 255.27 0)
			(effects
				(font
					(size 1.27 1.27)
					(thickness 0.15)
				)
				(justify left bottom)
				(hide yes)
			)
		)
		(property "Description" "SMD Chip Resistor, Jumper, 0 ohm, 100 mW, 0402 [1005 Metric], Thick Film, General Purpose"
			(at 76.2 270.51 0)
			(effects
				(font
					(size 1.27 1.27)
				)
				(justify left bottom)
				(hide yes)
			)
		)
		(property "MPN" "ERJ2GE0R00X"
			(at 76.2 257.81 0)
			(effects
				(font
					(size 1.27 1.27)
					(thickness 0.15)
				)
				(justify left bottom)
				(hide yes)
			)
		)
		(property "Manufacturer" "Panasonic"
			(at 76.2 260.35 0)
			(effects
				(font
					(size 1.27 1.27)
					(thickness 0.15)
				)
				(justify left bottom)
				(hide yes)
			)
		)
		(property "License" "Apache-2.0"
			(at 76.2 262.89 0)
			(effects
				(font
					(size 1.27 1.27)
					(thickness 0.15)
				)
				(justify left bottom)
				(hide yes)
			)
		)
		(property "Author" "Antmicro"
			(at 76.2 265.43 0)
			(effects
				(font
					(size 1.27 1.27)
					(thickness 0.15)
				)
				(justify left bottom)
				(hide yes)
			)
		)
		(property "Val" "0R"
			(at 55.118 236.22 0)
			(effects
				(font
					(size 1.27 1.27)
					(thickness 0.15)
				)
			)
		)
		(property "Tolerance" "~"
			(at 76.2 247.65 0)
			(effects
				(font
					(size 1.27 1.27)
				)
				(justify left bottom)
				(hide yes)
			)
		)
		(property "Current" "1A"
			(at 76.2 267.97 0)
			(effects
				(font
					(size 1.27 1.27)
					(thickness 0.15)
				)
				(justify left bottom)
				(hide yes)
			)
		)
		(pin "2"
		)
		(pin "1"
		)
		(instances
			(project "jetson-agx-thor-baseboard"
				(path ""
					(reference "R385")
					(unit 1)
				)
			)
		)
	)
	(symbol
		(lib_id "antmicropower:PWR_FLAG")
		(at 134.62 63.5 0)
		(unit 1)
		(exclude_from_sim no)
		(in_bom yes)
		(on_board yes)
		(dnp no)
		(property "Reference" "#FLG014"
			(at 134.62 61.595 0)
			(effects
				(font
					(size 1.27 1.27)
				)
				(hide yes)
			)
		)
		(property "Value" "PWR_FLAG"
			(at 134.62 59.69 0)
			(effects
				(font
					(size 1.27 1.27)
				)
			)
		)
		(property "Footprint" ""
			(at 134.62 63.5 0)
			(effects
				(font
					(size 1.27 1.27)
				)
				(hide yes)
			)
		)
		(property "Datasheet" ""
			(at 134.62 63.5 0)
			(effects
				(font
					(size 1.27 1.27)
				)
				(hide yes)
			)
		)
		(property "Description" ""
			(at 134.62 63.5 0)
			(effects
				(font
					(size 1.27 1.27)
				)
				(hide yes)
			)
		)
		(pin "1"
		)
		(instances
			(project "jetson-agx-thor-baseboard"
				(path ""
					(reference "#FLG014")
					(unit 1)
				)
			)
		)
	)
	(symbol
		(lib_id "antmicroResistors0402:R_10k_0402")
		(at 283.21 43.18 90)
		(unit 1)
		(exclude_from_sim no)
		(in_bom yes)
		(on_board yes)
		(dnp no)
		(property "Reference" "R152"
			(at 284.48 39.37 90)
			(effects
				(font
					(size 1.27 1.27)
				)
				(justify right)
			)
		)
		(property "Value" "R_10k_0402"
			(at 295.91 22.86 0)
			(effects
				(font
					(size 1.27 1.27)
					(thickness 0.15)
				)
				(justify left bottom)
				(hide yes)
			)
		)
		(property "Footprint" "antmicro-footprints:R_0402_1005Metric"
			(at 298.45 22.86 0)
			(effects
				(font
					(size 1.27 1.27)
					(thickness 0.15)
				)
				(justify left bottom)
				(hide yes)
			)
		)
		(property "Datasheet" "https://www.bourns.com/docs/product-datasheets/cr.pdf"
			(at 300.99 22.86 0)
			(effects
				(font
					(size 1.27 1.27)
					(thickness 0.15)
				)
				(justify left bottom)
				(hide yes)
			)
		)
		(property "Description" "SMD Chip Resistor, 10 kohm, ± 1%, 62.5 mW, 0402 [1005 Metric], Thick Film, General Purpose"
			(at 283.21 43.18 0)
			(effects
				(font
					(size 1.27 1.27)
				)
				(hide yes)
			)
		)
		(property "Manufacturer" "Bourns"
			(at 306.07 22.86 0)
			(effects
				(font
					(size 1.27 1.27)
					(thickness 0.15)
				)
				(justify left bottom)
				(hide yes)
			)
		)
		(property "MPN" "CR0402-FX-1002GLF"
			(at 303.53 22.86 0)
			(effects
				(font
					(size 1.27 1.27)
					(thickness 0.15)
				)
				(justify left bottom)
				(hide yes)
			)
		)
		(property "Val" "10k"
			(at 284.48 41.91 90)
			(effects
				(font
					(size 1.27 1.27)
					(thickness 0.15)
				)
				(justify right)
			)
		)
		(property "License" "Apache-2.0"
			(at 308.61 22.86 0)
			(effects
				(font
					(size 1.27 1.27)
					(thickness 0.15)
				)
				(justify left bottom)
				(hide yes)
			)
		)
		(property "Author" "Antmicro"
			(at 311.15 22.86 0)
			(effects
				(font
					(size 1.27 1.27)
					(thickness 0.15)
				)
				(justify left bottom)
				(hide yes)
			)
		)
		(property "Tolerance" "1%"
			(at 293.37 22.86 0)
			(effects
				(font
					(size 1.27 1.27)
				)
				(justify left bottom)
				(hide yes)
			)
		)
		(pin "1"
		)
		(pin "2"
		)
		(instances
			(project "usb_debug_pd"
				(path ""
					(reference "R?")
					(unit 1)
				)
			)
			(project "jetson-agx-thor-baseboard"
				(path ""
					(reference "R152")
					(unit 1)
				)
			)
		)
	)
	(symbol
		(lib_id "antmicroResistors0402:R_100k_0402")
		(at 158.75 215.9 0)
		(unit 1)
		(exclude_from_sim no)
		(in_bom yes)
		(on_board yes)
		(dnp no)
		(property "Reference" "R95"
			(at 163.83 215.265 0)
			(effects
				(font
					(size 1.27 1.27)
				)
				(justify left bottom)
			)
		)
		(property "Value" "R_100k_0402"
			(at 179.07 228.6 0)
			(effects
				(font
					(size 1.27 1.27)
					(thickness 0.15)
				)
				(justify left bottom)
				(hide yes)
			)
		)
		(property "Footprint" "antmicro-footprints:R_0402_1005Metric"
			(at 179.07 231.14 0)
			(effects
				(font
					(size 1.27 1.27)
					(thickness 0.15)
				)
				(justify left bottom)
				(hide yes)
			)
		)
		(property "Datasheet" "https://www.bourns.com/docs/product-datasheets/cr.pdf"
			(at 179.07 233.68 0)
			(effects
				(font
					(size 1.27 1.27)
					(thickness 0.15)
				)
				(justify left bottom)
				(hide yes)
			)
		)
		(property "Description" "SMD Chip Resistor, 100 kohm, ± 1%, 62.5 mW, 0402 [1005 Metric], Thick Film, General Purpose"
			(at 158.75 215.9 0)
			(effects
				(font
					(size 1.27 1.27)
				)
				(hide yes)
			)
		)
		(property "Manufacturer" "Bourns"
			(at 179.07 238.76 0)
			(effects
				(font
					(size 1.27 1.27)
					(thickness 0.15)
				)
				(justify left bottom)
				(hide yes)
			)
		)
		(property "MPN" "CR0402-FX-1003GLF"
			(at 179.07 236.22 0)
			(effects
				(font
					(size 1.27 1.27)
					(thickness 0.15)
				)
				(justify left bottom)
				(hide yes)
			)
		)
		(property "Val" "100k"
			(at 154.305 215.265 0)
			(effects
				(font
					(size 1.27 1.27)
					(thickness 0.15)
				)
				(justify left bottom)
			)
		)
		(property "License" "Apache-2.0"
			(at 179.07 241.3 0)
			(effects
				(font
					(size 1.27 1.27)
					(thickness 0.15)
				)
				(justify left bottom)
				(hide yes)
			)
		)
		(property "Author" "Antmicro"
			(at 179.07 243.84 0)
			(effects
				(font
					(size 1.27 1.27)
					(thickness 0.15)
				)
				(justify left bottom)
				(hide yes)
			)
		)
		(property "Tolerance" "1%"
			(at 179.07 226.06 0)
			(effects
				(font
					(size 1.27 1.27)
				)
				(justify left bottom)
				(hide yes)
			)
		)
		(pin "1"
		)
		(pin "2"
		)
		(instances
			(project "usb_debug_pd"
				(path ""
					(reference "R?")
					(unit 1)
				)
			)
			(project "jetson-agx-thor-baseboard"
				(path ""
					(reference "R95")
					(unit 1)
				)
			)
		)
	)
	(symbol
		(lib_id "antmicroTestPoints:TP_0.75mm_SMD")
		(at 271.78 34.29 180)
		(unit 1)
		(exclude_from_sim no)
		(in_bom no)
		(on_board yes)
		(dnp no)
		(property "Reference" "TP19"
			(at 267.97 34.29 0)
			(effects
				(font
					(size 1.27 1.27)
				)
				(justify left)
			)
		)
		(property "Value" "TP_0.75mm_SMD"
			(at 261.62 30.48 0)
			(effects
				(font
					(size 1.27 1.27)
					(thickness 0.15)
				)
				(justify left bottom)
				(hide yes)
			)
		)
		(property "Footprint" "antmicro-footprints:TP_SMD_0.75mm"
			(at 261.62 27.94 0)
			(effects
				(font
					(size 1.27 1.27)
					(thickness 0.15)
				)
				(justify left bottom)
				(hide yes)
			)
		)
		(property "Datasheet" ""
			(at 254 21.59 0)
			(effects
				(font
					(size 1.27 1.27)
					(thickness 0.15)
				)
				(justify left bottom)
				(hide yes)
			)
		)
		(property "Description" "SMT test point"
			(at 271.78 34.29 0)
			(effects
				(font
					(size 1.27 1.27)
				)
				(hide yes)
			)
		)
		(property "MPN" ""
			(at 260.985 22.86 0)
			(effects
				(font
					(size 1.27 1.27)
					(thickness 0.15)
				)
				(justify left bottom)
				(hide yes)
			)
		)
		(property "Manufacturer" ""
			(at 260.985 27.94 0)
			(effects
				(font
					(size 1.27 1.27)
					(thickness 0.15)
				)
				(justify left bottom)
				(hide yes)
			)
		)
		(property "Author" "Antmicro"
			(at 261.62 25.4 0)
			(effects
				(font
					(size 1.27 1.27)
					(thickness 0.15)
				)
				(justify left bottom)
				(hide yes)
			)
		)
		(property "License" "Apache-2.0"
			(at 261.62 22.86 0)
			(effects
				(font
					(size 1.27 1.27)
					(thickness 0.15)
				)
				(justify left bottom)
				(hide yes)
			)
		)
		(pin "1"
		)
		(instances
			(project "usb_debug_pd"
				(path ""
					(reference "TP?")
					(unit 1)
				)
			)
			(project "jetson-agx-thor-baseboard"
				(path ""
					(reference "TP19")
					(unit 1)
				)
			)
		)
	)
	(symbol
		(lib_id "antmicroResistors0402:R_0R_0402")
		(at 55.88 256.54 0)
		(unit 1)
		(exclude_from_sim no)
		(in_bom no)
		(on_board yes)
		(dnp yes)
		(property "Reference" "R387"
			(at 62.992 255.27 0)
			(effects
				(font
					(size 1.27 1.27)
					(thickness 0.15)
				)
			)
		)
		(property "Value" "R_0R_0402"
			(at 76.2 269.24 0)
			(effects
				(font
					(size 1.27 1.27)
					(thickness 0.15)
				)
				(justify left bottom)
				(hide yes)
			)
		)
		(property "Footprint" "antmicro-footprints:R_0402_1005Metric"
			(at 76.2 271.78 0)
			(effects
				(font
					(size 1.27 1.27)
					(thickness 0.15)
				)
				(justify left bottom)
				(hide yes)
			)
		)
		(property "Datasheet" "https://industrial.panasonic.com/cdbs/www-data/pdf/RDA0000/AOA0000C301.pdf"
			(at 76.2 274.32 0)
			(effects
				(font
					(size 1.27 1.27)
					(thickness 0.15)
				)
				(justify left bottom)
				(hide yes)
			)
		)
		(property "Description" "SMD Chip Resistor, Jumper, 0 ohm, 100 mW, 0402 [1005 Metric], Thick Film, General Purpose"
			(at 76.2 289.56 0)
			(effects
				(font
					(size 1.27 1.27)
				)
				(justify left bottom)
				(hide yes)
			)
		)
		(property "MPN" "ERJ2GE0R00X"
			(at 76.2 276.86 0)
			(effects
				(font
					(size 1.27 1.27)
					(thickness 0.15)
				)
				(justify left bottom)
				(hide yes)
			)
		)
		(property "Manufacturer" "Panasonic"
			(at 76.2 279.4 0)
			(effects
				(font
					(size 1.27 1.27)
					(thickness 0.15)
				)
				(justify left bottom)
				(hide yes)
			)
		)
		(property "License" "Apache-2.0"
			(at 76.2 281.94 0)
			(effects
				(font
					(size 1.27 1.27)
					(thickness 0.15)
				)
				(justify left bottom)
				(hide yes)
			)
		)
		(property "Author" "Antmicro"
			(at 76.2 284.48 0)
			(effects
				(font
					(size 1.27 1.27)
					(thickness 0.15)
				)
				(justify left bottom)
				(hide yes)
			)
		)
		(property "Val" "0R"
			(at 55.118 255.27 0)
			(effects
				(font
					(size 1.27 1.27)
					(thickness 0.15)
				)
			)
		)
		(property "Tolerance" "~"
			(at 76.2 266.7 0)
			(effects
				(font
					(size 1.27 1.27)
				)
				(justify left bottom)
				(hide yes)
			)
		)
		(property "Current" "1A"
			(at 76.2 287.02 0)
			(effects
				(font
					(size 1.27 1.27)
					(thickness 0.15)
				)
				(justify left bottom)
				(hide yes)
			)
		)
		(pin "2"
		)
		(pin "1"
		)
		(instances
			(project "jetson-agx-thor-baseboard"
				(path ""
					(reference "R387")
					(unit 1)
				)
			)
		)
	)
	(sheet_instances
		(path "/"
			(page "1")
		)
	)
)
